G04 ================== begin FILE IDENTIFICATION RECORD ==================*
G04 Layout Name:  D:/<user>/Wistron_project/16317-1/gbr/16317-1.brd*
G04 Film Name:    L6*
G04 File Format:  Gerber RS274X*
G04 File Origin:  Cadence Allegro 16.5-S056*
G04 Origin Date:  Fri Jun 09 15:53:38 2017*
G04 *
G04 Layer:  VIA CLASS/L6*
G04 Layer:  PIN/L6*
G04 Layer:  ETCH/L6*
G04 Layer:  DRAWING FORMAT/LAYER_PCB_STORY*
G04 Layer:  DRAWING FORMAT/LAYER_L6*
G04 *
G04 Offset:    (0.00 0.00)*
G04 Mirror:    No*
G04 Mode:      Positive*
G04 Rotation:  0*
G04 FullContactRelief:  No*
G04 UndefLineWidth:     6.00*
G04 ================== end FILE IDENTIFICATION RECORD ====================*
%FSLAX35Y35*MOIN*%
%IR0*IPPOS*OFA0.00000B0.00000*MIA0B0*SFA1.00000B1.00000*%
%ADD12C,.02*%
%ADD15C,.03*%
%ADD11C,.022*%
%ADD14C,.034*%
%ADD10C,.028*%
%ADD13C,.056*%
%ADD16C,.048*%
%ADD17C,.01*%
%ADD18C,.04*%
%ADD19C,.06*%
%ADD20C,.006*%
%ADD21C,.0055*%
%ADD22C,.00475*%
%ADD23C,.00575*%
%ADD25C,.05204*%
%ADD24C,.04604*%
G75*
%LPD*%
G75*
G36*
G01X787402Y192768D02*
G03X780461Y185827I0J-6941D01*
G01Y3937D01*
G02X779528Y3004I-933J0D01*
G01X3937D01*
G02X3004Y3937I0J933D01*
G01Y1456693D01*
G02X3937Y1457626I933J0D01*
G01X7874D01*
G03X14815Y1464567I0J6941D01*
G01Y1515748D01*
G02X15748Y1516681I933J0D01*
G01X60039D01*
G02X60972Y1515748I0J-933D01*
G01Y1509055D01*
G03X67913Y1502114I6941J0D01*
G01X93504D01*
G03X100445Y1509055I0J6941D01*
G01Y1515748D01*
G02X101378Y1516681I933J0D01*
G01X280709D01*
G02X281642Y1515748I0J-933D01*
G01Y1500000D01*
G03X288583Y1493059I6941J0D01*
G01X493307D01*
G03X500248Y1500000I0J6941D01*
G01Y1515748D01*
G02X501181Y1516681I933J0D01*
G01X680512D01*
G02X681445Y1515748I0J-933D01*
G01Y1509055D01*
G03X688386Y1502114I6941J0D01*
G01X713976D01*
G03X720917Y1509055I0J6941D01*
G01Y1515748D01*
G02X721850Y1516681I933J0D01*
G01X775591D01*
G02X776524Y1515748I0J-933D01*
G01Y1500000D01*
G03X783465Y1493059I6941J0D01*
G01X988189D01*
G03X995130Y1500000I0J6941D01*
G01Y1515748D01*
G02X996063Y1516681I933J0D01*
G01X1059198D01*
G02X1059856Y1516408I-1J-933D01*
G01X1069361Y1506903D01*
G02X1069634Y1506245I-660J-660D01*
G01Y1421260D01*
G03X1076575Y1414319I6941J0D01*
G01X1085630D01*
G03X1092571Y1421260I0J6941D01*
G01Y1506245D01*
G02X1092844Y1506903I933J-1D01*
G01X1102349Y1516408D01*
G02X1103007Y1516681I659J-660D01*
G01X1207283D01*
G02X1208216Y1515748I0J-933D01*
G01Y1509055D01*
G03X1215157Y1502114I6941J0D01*
G01X1240748D01*
G03X1247689Y1509055I0J6941D01*
G01Y1515748D01*
G02X1248622Y1516681I933J0D01*
G01X1427953D01*
G02X1428886Y1515748I0J-933D01*
G01Y1500000D01*
G03X1435827Y1493059I6941J0D01*
G01X1640551D01*
G03X1647492Y1500000I0J6941D01*
G01Y1515748D01*
G02X1648425Y1516681I933J0D01*
G01X1827756D01*
G02X1828689Y1515748I0J-933D01*
G01Y1509055D01*
G03X1835630Y1502114I6941J0D01*
G01X1861220D01*
G03X1868161Y1509055I0J6941D01*
G01Y1515748D01*
G02X1869094Y1516681I933J0D01*
G01X1919094D01*
G02X1920027Y1515748I0J-933D01*
G01Y1464567D01*
G03X1926967Y1457626I6941J0D01*
G01X1930906D01*
G02X1931839Y1456693I0J-933D01*
G01Y1342534D01*
X1926843D01*
Y1452631D01*
G02X1915031Y1464567I125J11936D01*
G01Y1511685D01*
X1873157D01*
Y1509055D01*
G02X1861220Y1497118I-11937J0D01*
G01X1835630D01*
G02X1823693Y1509055I0J11937D01*
G01Y1511685D01*
X1652488D01*
Y1500000D01*
G02X1640551Y1488063I-11937J0D01*
G01X1435827D01*
G02X1423890Y1500000I0J11937D01*
G01Y1511685D01*
X1252685D01*
Y1509055D01*
G02X1240748Y1497118I-11937J0D01*
G01X1215157D01*
G02X1203220Y1509055I0J11937D01*
G01Y1511685D01*
X1104691D01*
X1097567Y1504561D01*
Y1421260D01*
G02X1085630Y1409323I-11937J0D01*
G01X1076575D01*
G02X1064638Y1421260I0J11937D01*
G01Y1504561D01*
X1057514Y1511685D01*
X1000126D01*
Y1500000D01*
G02X988189Y1488063I-11937J0D01*
G01X783465D01*
G02X771528Y1500000I0J11937D01*
G01Y1511685D01*
X725913D01*
Y1509055D01*
G02X713976Y1497118I-11937J0D01*
G01X688386D01*
G02X676449Y1509055I0J11937D01*
G01Y1511685D01*
X505244D01*
Y1500000D01*
G02X493307Y1488063I-11937J0D01*
G01X288583D01*
G02X276646Y1500000I0J11937D01*
G01Y1511685D01*
X105441D01*
Y1509055D01*
G02X93504Y1497118I-11937J0D01*
G01X67913D01*
G02X55976Y1509055I0J11937D01*
G01Y1511685D01*
X19811D01*
Y1464567D01*
G02X8000Y1452631I-11937J0D01*
G01Y8000D01*
X775465D01*
Y185827D01*
G02X787402Y197764I11937J0D01*
G01X806961D01*
Y244095D01*
G02X818897Y256031I11937J-1D01*
G01X832344D01*
G03X835374I1515J2237D01*
G01X846517D01*
G03X849547I1515J2237D01*
G01X860690D01*
G03X863720I1515J2237D01*
G01X874863D01*
G03X877893I1515J2237D01*
G01X891041D01*
Y251035D01*
X818897D01*
G03X811957Y244095I1J-6941D01*
G01Y193701D01*
G02X811024Y192768I-933J0D01*
G01X787402D01*
G37*
G36*
G01X524855Y1438660D02*
G03Y1434064I-133J-2298D01*
G02X525278Y1433665I23J-399D01*
G01Y1421514D01*
X522345Y1418581D01*
X522321Y1418567D01*
G03X521439Y1417675I1134J-2003D01*
G01X518132Y1414368D01*
X499132D01*
X472000Y1441500D01*
X323008D01*
X254259Y1372751D01*
X254291D01*
X253540Y1372000D01*
X147500D01*
X146500Y1373000D01*
Y1396500D01*
X170500Y1420500D01*
Y1436500D01*
X172500Y1438500D01*
X243000D01*
X285000Y1480500D01*
X485500D01*
X514500Y1451500D01*
X521222D01*
X525278Y1447444D01*
Y1439059D01*
G02X524855Y1438660I-400J0D01*
G37*
G36*
G01X286500Y1364000D02*
X288500Y1366000D01*
X398500D01*
X401242Y1363258D01*
Y1308742D01*
X397500Y1305000D01*
X288500D01*
X286500Y1307000D01*
Y1364000D01*
G37*
G36*
G01X599811Y1288250D02*
X597750Y1290311D01*
Y1302811D01*
X595837Y1304724D01*
X536520D01*
G02X536396Y1305504I0J400D01*
G03X531496Y1336222I-4900J14968D01*
G01X511496D01*
G03X506596Y1305504I0J-15750D01*
G02X506472Y1304724I-124J-380D01*
G01X410337D01*
X405250Y1309811D01*
Y1362689D01*
X408750Y1366189D01*
Y1433798D01*
X409952Y1435000D01*
X430000D01*
X441500Y1423500D01*
X484200D01*
X497450Y1410250D01*
X632250D01*
Y1295750D01*
X621689D01*
X619750Y1293811D01*
Y1288811D01*
X619189Y1288250D01*
X599811D01*
G37*
G36*
G01X803739Y1295750D02*
X655100D01*
Y1410250D01*
X803589D01*
X804900Y1408939D01*
Y1296911D01*
X803739Y1295750D01*
G37*
G36*
G01X689700Y1465900D02*
Y1460788D01*
X689540Y1460756D01*
G03X688448Y1460200I461J-2256D01*
G01X679100D01*
X676200Y1463100D01*
Y1467000D01*
X679600Y1470400D01*
X681800D01*
X682300Y1469900D01*
Y1467600D01*
X683300Y1466600D01*
X684710D01*
G03X686990I1140J2000D01*
G01X689000D01*
X689700Y1465900D01*
G37*
G36*
G01X821000Y1299000D02*
X822000Y1300000D01*
X835000D01*
X837000Y1302000D01*
Y1326000D01*
X834500Y1328500D01*
X822000D01*
X821000Y1329500D01*
Y1336000D01*
X822000Y1337000D01*
X833500D01*
X837000Y1340500D01*
Y1364500D01*
X834500Y1367000D01*
X822000D01*
X821000Y1368000D01*
Y1374000D01*
X822000Y1375000D01*
X834500D01*
X837000Y1377500D01*
Y1387500D01*
X832500Y1392000D01*
Y1402500D01*
X834500Y1404500D01*
X841500D01*
X843500Y1402500D01*
Y1296000D01*
X840000Y1292500D01*
X822000D01*
X821000Y1293500D01*
Y1299000D01*
G37*
G36*
G01X845000Y1398500D02*
Y1413500D01*
X847000Y1415500D01*
X851000D01*
X854000Y1412500D01*
Y1398800D01*
X852700Y1397500D01*
X846000D01*
X845000Y1398500D01*
G37*
G36*
G01X933100Y251100D02*
X932500Y251700D01*
Y326200D01*
X998300Y392000D01*
X1077200D01*
X1079200Y390000D01*
Y252200D01*
X1078100Y251100D01*
X933100D01*
G37*
G36*
G01X949964Y1187764D02*
G03X948424Y1188618I-2263J-2265D01*
G01X948369Y1188631D01*
X945000Y1192000D01*
Y1231254D01*
G03Y1234746I-1500J1746D01*
G01Y1235500D01*
X946000Y1236500D01*
X990500D01*
X993000Y1234000D01*
Y1197000D01*
X980500Y1184500D01*
X953228D01*
X949964Y1187764D01*
G37*
G36*
G01X1023718Y1388189D02*
Y1300118D01*
X1022400Y1298800D01*
X982600D01*
X981200Y1300200D01*
Y1354500D01*
X983300Y1356600D01*
X983317D01*
X986917Y1360200D01*
Y1393319D01*
X988836Y1395238D01*
X1016669D01*
X1023718Y1388189D01*
G37*
G36*
G01X1029818Y1310189D02*
X1028918Y1311089D01*
Y1323689D01*
X1029218Y1323989D01*
X1039394D01*
X1039960Y1323423D01*
X1057290D01*
X1058556Y1324689D01*
Y1331402D01*
X1056791Y1333167D01*
X1029762D01*
X1028918Y1334011D01*
Y1351721D01*
X1029296Y1352099D01*
X1039892D01*
X1040785Y1351206D01*
X1057607D01*
X1058451Y1352050D01*
Y1357775D01*
X1056996Y1359230D01*
G03X1052885Y1359319I-2078J-991D01*
G01X1029548D01*
X1028918Y1359949D01*
Y1379830D01*
X1029249Y1380161D01*
X1052940D01*
G03X1056896I1978J1178D01*
G01X1069174D01*
X1071668Y1377667D01*
Y1313483D01*
X1068374Y1310189D01*
X1029818D01*
G37*
G36*
G01X1062059Y244094D02*
G03X1061783Y246030I-6940J-2D01*
G02X1062168Y246542I384J112D01*
G01X1066802D01*
G02X1067055Y244101I-11684J-2445D01*
G01Y197764D01*
X1220472D01*
G02X1232409Y185827I0J-11937D01*
G01Y8000D01*
X1926843D01*
Y1341021D01*
X1931839D01*
Y3937D01*
G02X1930906Y3004I-933J0D01*
G01X1228346D01*
G02X1227413Y3937I0J933D01*
G01Y185827D01*
G03X1220472Y192768I-6941J0D01*
G01X1062992D01*
G02X1062059Y193701I0J933D01*
G01Y244094D01*
G37*
G36*
G01X1133100Y1290300D02*
X1125231Y1298169D01*
X1125217Y1298219D01*
G03X1123619Y1299817I-2217J-619D01*
G01X1123569Y1299831D01*
X1118800Y1304600D01*
Y1312600D01*
X1119600Y1313400D01*
X1121001D01*
X1121015Y1313398D01*
G03X1121677I331J2278D01*
G01X1121691Y1313400D01*
X1122900D01*
X1123700Y1314200D01*
Y1320900D01*
X1122300Y1322300D01*
X1115600D01*
X1113902Y1323998D01*
Y1333295D01*
X1115005Y1334398D01*
X1131102D01*
X1132600Y1332900D01*
Y1312100D01*
X1134224Y1310476D01*
X1159884D01*
X1159941Y1310419D01*
X1190651D01*
X1191482Y1311250D01*
Y1348174D01*
X1192089Y1348781D01*
X1195227D01*
X1195830Y1348178D01*
Y1343926D01*
X1196533Y1343223D01*
X1205198D01*
X1205901Y1343926D01*
Y1348046D01*
X1206636Y1348781D01*
X1209457D01*
X1210602Y1347636D01*
Y1310930D01*
X1212155Y1309377D01*
X1223180D01*
X1224510Y1310707D01*
Y1350989D01*
X1225021Y1351500D01*
X1228798D01*
X1229785Y1350513D01*
Y1345205D01*
X1230690Y1344300D01*
X1234900D01*
X1235396Y1344796D01*
X1235526Y1344727D01*
G03X1236344Y1349051I1074J2036D01*
G02X1235900Y1349448I-44J397D01*
G01Y1352100D01*
X1109500Y1478500D01*
Y1486000D01*
X1110500Y1487000D01*
X1120729D01*
X1245200Y1362529D01*
Y1297100D01*
X1243200Y1295100D01*
X1238384D01*
X1159013Y1295087D01*
X1154226Y1290300D01*
X1133100D01*
G37*
%LPC*%
G75*
G36*
G01X239478Y1427006D02*
G03X239172Y1426393I32J-399D01*
G02X236770Y1427594I-2198J-1393D01*
G03X237076Y1428207I-32J399D01*
G02X239478Y1427006I2198J1393D01*
G37*
G36*
G01X1045739Y304430D02*
G03Y303839I270J-296D01*
G02X1040875I-2432J-2657D01*
G03Y304430I-270J295D01*
G02X1040876Y309745I2432J2657D01*
G03Y310335I-270J295D01*
G02X1045738I2431J2658D01*
G03Y309745I270J-295D01*
G02X1045739Y304430I-2431J-2658D01*
G37*
G36*
G01X1033141D02*
G03Y303839I270J-296D01*
G02X1028277I-2432J-2657D01*
G03Y304430I-270J295D01*
G02X1028278Y309745I2432J2657D01*
G03Y310335I-270J295D01*
G02X1033140I2431J2658D01*
G03Y309745I270J-295D01*
G02X1033141Y304430I-2431J-2658D01*
G37*
G36*
G01X1017392D02*
G03Y303839I270J-296D01*
G02X1012528I-2432J-2657D01*
G03Y304430I-270J295D01*
G02X1012529Y309745I2432J2657D01*
G03Y310335I-270J295D01*
G02X1017391I2431J2658D01*
G03Y309745I270J-295D01*
G02X1017392Y304430I-2431J-2658D01*
G37*
G36*
G01X1004794D02*
G03Y303839I270J-296D01*
G02X999930I-2432J-2657D01*
G03Y304430I-270J295D01*
G02X999931Y309745I2432J2657D01*
G03Y310335I-270J295D01*
G02X1004793I2431J2658D01*
G03Y309745I270J-295D01*
G02X1004794Y304430I-2431J-2658D01*
G37*
G36*
G01X989046D02*
G03Y303839I270J-296D01*
G02X984182I-2432J-2657D01*
G03Y304430I-270J295D01*
G02X984183Y309745I2432J2657D01*
G03Y310335I-270J295D01*
G02X989045I2431J2658D01*
G03Y309745I270J-295D01*
G02X989046Y304430I-2431J-2658D01*
G37*
G36*
G01X976447D02*
G03Y303839I270J-296D01*
G02X971583I-2432J-2657D01*
G03Y304430I-270J295D01*
G02X971584Y309745I2432J2657D01*
G03Y310335I-270J295D01*
G02X976446I2431J2658D01*
G03Y309745I270J-295D01*
G02X976447Y304430I-2431J-2658D01*
G37*
G36*
G01X989046Y281792D02*
G03Y281201I270J-295D01*
G02X984182I-2432J-2657D01*
G03Y281792I-270J296D01*
G02X984183Y287107I2432J2657D01*
G03Y287697I-270J295D01*
G02X989045I2431J2658D01*
G03Y287107I270J-295D01*
G02X989046Y281792I-2431J-2658D01*
G37*
G36*
G01X976447D02*
G03Y281201I270J-295D01*
G02X971583I-2432J-2657D01*
G03Y281792I-270J296D01*
G02X971584Y287107I2432J2657D01*
G03Y287697I-270J295D01*
G02X976446I2431J2658D01*
G03Y287107I270J-295D01*
G02X976447Y281792I-2431J-2658D01*
G37*
G36*
G01X989045Y259154D02*
G03Y258564I270J-295D01*
G02X984183I-2431J-2658D01*
G03Y259154I-270J295D01*
G02X984182Y264469I2431J2658D01*
G03Y265060I-270J296D01*
G02X989046I2432J2657D01*
G03Y264469I270J-295D01*
G02X989045Y259154I-2432J-2657D01*
G37*
G36*
G01X976446D02*
G03Y258564I270J-295D01*
G02X971584I-2431J-2658D01*
G03Y259154I-270J295D01*
G02X971583Y264469I2431J2658D01*
G03Y265060I-270J296D01*
G02X976447I2432J2657D01*
G03Y264469I270J-295D01*
G02X976446Y259154I-2432J-2657D01*
G37*
G36*
G01X1034958Y372802D02*
G02X1033273Y372022I42J-2302D01*
G03X1032966Y372686I-300J264D01*
G02X1032097Y377136I-42J2302D01*
G03X1032115Y377876I-143J374D01*
G02X1033873Y377833I931J2105D01*
G03X1033855Y377093I143J-374D01*
G02X1034651Y373466I-931J-2105D01*
G03X1034958Y372802I300J-264D01*
G37*
G36*
G01X961204Y1234548D02*
G03X961796I296J269D01*
G02X965204I1704J-1548D01*
G03X965796I296J269D01*
G02Y1231452I1704J-1548D01*
G03X965204I-296J-269D01*
G02X961796I-1704J1548D01*
G03X961204I-296J-269D01*
G02Y1234548I-1704J1548D01*
G37*
G36*
G01X984048Y1199296D02*
G03Y1198704I269J-296D01*
G02X980952I-1548J-1704D01*
G03Y1199296I-269J296D01*
G02X984048I1548J1704D01*
G37*
G54D25*
X233074Y1429500D03*
X237235Y1419039D03*
X1012000Y371369D03*
X1015537Y365911D03*
G54D24*
X188274Y1416600D03*
X175249Y1434075D03*
X209374Y1416300D03*
X505224Y1424156D03*
X503035Y1444331D03*
X948298Y1215500D03*
X951500Y1233000D03*
X957000Y1207500D03*
X953100Y1211400D03*
X953000Y1203600D03*
X952500Y1193300D03*
X971700Y1193100D03*
X982500Y1217000D03*
Y1209000D03*
X960900Y1211400D03*
Y1203600D03*
%LPD*%
G75*
G54D10*
X100412Y6000D03*
X95412D03*
X90412D03*
X85412D03*
X80412D03*
X75412D03*
X70412D03*
X65412D03*
X60412D03*
X55412D03*
X50412D03*
X45412D03*
X40412D03*
X35412D03*
X30412D03*
X25412D03*
X20412D03*
X15412D03*
X10412D03*
X6000Y6588D03*
Y11588D03*
Y16588D03*
Y21588D03*
Y26588D03*
Y31588D03*
Y36588D03*
Y41588D03*
Y46588D03*
Y51588D03*
Y56588D03*
Y61588D03*
Y66588D03*
Y71588D03*
Y76588D03*
Y81588D03*
Y86588D03*
Y91588D03*
Y96588D03*
Y101588D03*
Y106588D03*
Y111588D03*
Y116588D03*
Y121588D03*
Y126588D03*
Y131588D03*
Y136588D03*
Y141588D03*
Y146588D03*
Y151588D03*
Y156588D03*
Y161588D03*
Y166588D03*
Y171588D03*
Y176588D03*
Y181588D03*
Y186588D03*
Y191588D03*
Y196588D03*
Y201588D03*
Y206588D03*
Y211588D03*
Y216588D03*
Y221588D03*
Y226588D03*
Y231588D03*
Y236588D03*
Y241588D03*
Y246588D03*
Y251588D03*
Y256588D03*
Y261588D03*
Y266588D03*
Y271588D03*
Y276588D03*
Y281588D03*
Y286588D03*
Y291588D03*
Y296588D03*
Y301588D03*
Y306588D03*
Y311588D03*
Y316588D03*
Y321588D03*
Y326588D03*
Y331588D03*
Y336588D03*
Y341588D03*
Y346588D03*
Y351588D03*
Y356588D03*
Y361588D03*
Y366588D03*
Y371588D03*
Y376588D03*
Y441588D03*
Y436588D03*
Y431588D03*
Y426588D03*
Y421588D03*
Y416588D03*
Y411588D03*
Y406588D03*
Y386588D03*
Y391588D03*
Y396588D03*
Y401588D03*
Y446588D03*
Y451588D03*
Y456588D03*
Y461588D03*
Y381588D03*
Y466588D03*
Y471588D03*
Y476588D03*
Y481588D03*
Y486588D03*
Y491588D03*
Y496588D03*
Y501588D03*
Y506588D03*
Y511588D03*
Y516588D03*
Y521588D03*
Y526588D03*
Y531588D03*
Y536588D03*
Y541588D03*
Y546588D03*
Y551588D03*
Y556588D03*
Y561588D03*
Y566588D03*
Y571588D03*
Y576588D03*
Y581588D03*
Y586588D03*
Y591588D03*
Y596588D03*
Y601588D03*
Y606588D03*
Y611588D03*
Y616588D03*
Y621588D03*
Y626588D03*
Y631588D03*
Y636588D03*
Y641588D03*
Y646588D03*
Y651588D03*
Y656588D03*
Y661588D03*
Y666588D03*
Y671588D03*
Y676588D03*
Y681588D03*
Y686588D03*
Y691588D03*
Y696588D03*
Y701588D03*
Y706588D03*
Y711588D03*
Y716588D03*
Y721588D03*
Y726588D03*
Y731588D03*
Y736588D03*
Y741588D03*
Y746588D03*
Y751588D03*
Y756588D03*
Y761588D03*
Y766588D03*
Y771588D03*
Y776588D03*
Y781588D03*
Y786588D03*
Y791588D03*
Y796588D03*
Y801588D03*
Y806588D03*
Y811588D03*
Y816588D03*
Y821588D03*
Y826588D03*
Y831588D03*
Y836588D03*
Y841588D03*
Y846588D03*
Y851588D03*
Y856588D03*
Y861588D03*
Y866588D03*
Y871588D03*
Y876588D03*
Y881588D03*
Y886588D03*
Y891588D03*
Y896588D03*
Y901588D03*
Y906588D03*
Y911588D03*
Y916588D03*
Y921588D03*
Y926588D03*
Y931588D03*
Y936588D03*
Y941588D03*
Y946588D03*
Y951588D03*
Y956588D03*
Y961588D03*
Y966588D03*
Y971588D03*
Y976588D03*
Y981588D03*
Y986588D03*
Y991588D03*
Y996588D03*
Y1001588D03*
Y1006588D03*
Y1011588D03*
Y1016588D03*
Y1021588D03*
Y1026588D03*
Y1031588D03*
Y1036588D03*
Y1041588D03*
Y1046588D03*
Y1051588D03*
Y1056588D03*
Y1061588D03*
Y1066588D03*
Y1071588D03*
Y1076588D03*
Y1081588D03*
Y1086588D03*
Y1091588D03*
Y1096588D03*
Y1101588D03*
Y1106588D03*
Y1111588D03*
Y1116588D03*
Y1121588D03*
Y1126588D03*
Y1131588D03*
Y1136588D03*
Y1141588D03*
Y1146588D03*
Y1151588D03*
Y1156588D03*
Y1161588D03*
Y1166588D03*
Y1171588D03*
Y1176588D03*
Y1181588D03*
Y1186588D03*
Y1191588D03*
Y1196588D03*
Y1201588D03*
Y1206588D03*
Y1211588D03*
Y1216588D03*
Y1221588D03*
Y1226588D03*
Y1231588D03*
Y1236588D03*
Y1321588D03*
Y1326588D03*
Y1331588D03*
Y1286588D03*
Y1291588D03*
Y1296588D03*
Y1301588D03*
Y1306588D03*
Y1311588D03*
Y1316588D03*
Y1241588D03*
Y1246588D03*
Y1251588D03*
Y1256588D03*
Y1261588D03*
Y1266588D03*
Y1271588D03*
Y1276588D03*
Y1281588D03*
Y1421588D03*
Y1416588D03*
Y1411588D03*
Y1406588D03*
Y1401588D03*
Y1396588D03*
Y1391588D03*
Y1386588D03*
Y1381588D03*
Y1376588D03*
Y1371588D03*
Y1366588D03*
Y1361588D03*
Y1356588D03*
Y1351588D03*
Y1346588D03*
Y1341588D03*
Y1426588D03*
Y1336588D03*
Y1451588D03*
Y1446588D03*
Y1441588D03*
Y1436588D03*
Y1431588D03*
X99000Y1501000D03*
X61500Y1502000D03*
X87539Y1499118D03*
X82539D03*
X77539D03*
X72539D03*
X67539D03*
X92539D03*
X11000Y1455500D03*
X15500Y1458500D03*
X17811Y1462693D03*
Y1467693D03*
Y1472693D03*
Y1477693D03*
Y1482693D03*
Y1487693D03*
Y1492693D03*
Y1497693D03*
Y1502693D03*
Y1507693D03*
X17500Y1512000D03*
X21819Y1513685D03*
X26819D03*
X31819D03*
X36819D03*
X41819D03*
X46819D03*
X51819D03*
X56819D03*
X58500Y1508000D03*
X195412Y6000D03*
X190412D03*
X185412D03*
X180412D03*
X175412D03*
X170412D03*
X165412D03*
X160412D03*
X155412D03*
X150412D03*
X145412D03*
X140412D03*
X135412D03*
X130412D03*
X125412D03*
X120412D03*
X115412D03*
X110412D03*
X105412D03*
X180000Y1424000D03*
Y1430000D03*
X186000Y1424000D03*
Y1430000D03*
X152000Y1377000D03*
Y1383000D03*
X158000Y1377000D03*
Y1383000D03*
X170000D03*
Y1377000D03*
X164000Y1383000D03*
Y1377000D03*
X102000Y1505500D03*
X177433Y1513685D03*
X182433D03*
X187433D03*
X192433D03*
X147433D03*
X152433D03*
X157433D03*
X162433D03*
X167433D03*
X172433D03*
X103000Y1511000D03*
X107433Y1513685D03*
X112433D03*
X117433D03*
X122433D03*
X127433D03*
X132433D03*
X137433D03*
X142433D03*
X290412Y6000D03*
X285412D03*
X280412D03*
X275412D03*
X270412D03*
X265412D03*
X260412D03*
X255412D03*
X250412D03*
X245412D03*
X240412D03*
X235412D03*
X230412D03*
X225412D03*
X220412D03*
X215412D03*
X210412D03*
X205412D03*
X200412D03*
X283000Y1492000D03*
X279000Y1498500D03*
X197433Y1513685D03*
X202433D03*
X207433D03*
X212433D03*
X217433D03*
X222433D03*
X227433D03*
X232433D03*
X237433D03*
X242433D03*
X247433D03*
X252433D03*
X257433D03*
X262433D03*
X267433D03*
X272433D03*
X277433D03*
X278646Y1509398D03*
Y1504398D03*
X288685Y1490063D03*
X385412Y6000D03*
X380412D03*
X375412D03*
X370412D03*
X365412D03*
X360412D03*
X355412D03*
X350412D03*
X345412D03*
X340412D03*
X335412D03*
X330412D03*
X325412D03*
X320412D03*
X315412D03*
X310412D03*
X305412D03*
X300412D03*
X295412D03*
X293685Y1490063D03*
X298685D03*
X303685D03*
X308685D03*
X313685D03*
X318685D03*
X323685D03*
X328685D03*
X333685D03*
X338685D03*
X343685D03*
X348685D03*
X353685D03*
X358685D03*
X363685D03*
X368685D03*
X373685D03*
X378685D03*
X383685D03*
X480412Y6000D03*
X475412D03*
X470412D03*
X465412D03*
X460412D03*
X455412D03*
X450412D03*
X445412D03*
X440412D03*
X435412D03*
X430412D03*
X425412D03*
X420412D03*
X415412D03*
X410412D03*
X405412D03*
X400412D03*
X395412D03*
X390412D03*
X388685Y1490063D03*
X393685D03*
X398685D03*
X403685D03*
X408685D03*
X413685D03*
X418685D03*
X423685D03*
X428685D03*
X433685D03*
X438685D03*
X443685D03*
X448685D03*
X453685D03*
X458685D03*
X463685D03*
X468685D03*
X473685D03*
X478685D03*
X575412Y6000D03*
X570412D03*
X565412D03*
X560412D03*
X555412D03*
X550412D03*
X545412D03*
X540412D03*
X535412D03*
X530412D03*
X525412D03*
X520412D03*
X515412D03*
X510412D03*
X505412D03*
X500412D03*
X495412D03*
X490412D03*
X485412D03*
X501000Y1494000D03*
X503000Y1499000D03*
X494500Y1490500D03*
X574937Y1513685D03*
X569937D03*
X564937D03*
X559937D03*
X554937D03*
X549937D03*
X544937D03*
X539937D03*
X534937D03*
X529937D03*
X524937D03*
X483685Y1490063D03*
X488685D03*
X503244Y1504378D03*
Y1509378D03*
X504937Y1513685D03*
X509937D03*
X514937D03*
X519937D03*
X513917Y1447297D03*
X507917D03*
X519717D03*
X670412Y6000D03*
X665412D03*
X660412D03*
X655412D03*
X650412D03*
X645412D03*
X640412D03*
X635412D03*
X630412D03*
X625412D03*
X620412D03*
X615412D03*
X610412D03*
X605412D03*
X600412D03*
X595412D03*
X590412D03*
X585412D03*
X580412D03*
X669937Y1513685D03*
X659937D03*
X654937D03*
X649937D03*
X644937D03*
X639937D03*
X634937D03*
X629937D03*
X624937D03*
X619937D03*
X614937D03*
X609937D03*
X604937D03*
X599937D03*
X594937D03*
X589937D03*
X584937D03*
X579937D03*
X664937D03*
X765412Y6000D03*
X760412D03*
X755412D03*
X750412D03*
X745412D03*
X740412D03*
X735412D03*
X730412D03*
X725412D03*
X720412D03*
X715412D03*
X710412D03*
X705412D03*
X700412D03*
X695412D03*
X690412D03*
X685412D03*
X680412D03*
X675412D03*
X722000Y1503500D03*
X718500Y1500000D03*
X680500Y1503500D03*
X674937Y1513685D03*
X688012Y1499118D03*
X693012D03*
X698012D03*
X703012D03*
X708012D03*
X713012D03*
X724000Y1509500D03*
X725551Y1513685D03*
X730551D03*
X735551D03*
X740551D03*
X745551D03*
X750551D03*
X755551D03*
X760551D03*
X765551D03*
X678500Y1510500D03*
X777465Y93947D03*
Y88947D03*
Y83947D03*
Y78947D03*
Y73947D03*
Y68947D03*
Y63947D03*
Y58947D03*
Y53947D03*
Y48947D03*
Y43947D03*
Y38947D03*
Y33947D03*
Y28947D03*
Y23947D03*
Y18947D03*
Y13947D03*
X778000Y9500D03*
X775412Y6000D03*
X770412D03*
X777465Y183947D03*
Y178947D03*
Y173947D03*
Y168947D03*
Y163947D03*
Y158947D03*
Y153947D03*
Y148947D03*
Y143947D03*
Y138947D03*
Y133947D03*
Y128947D03*
Y123947D03*
Y118947D03*
Y113947D03*
Y108947D03*
Y103947D03*
Y98947D03*
X809500Y197500D03*
X805522Y195764D03*
X808961Y201678D03*
Y206678D03*
Y211678D03*
Y216678D03*
Y236678D03*
Y231678D03*
Y226678D03*
Y221678D03*
Y241678D03*
X779022Y190764D03*
X784022Y194764D03*
X800522Y195764D03*
X795522D03*
X790522D03*
X779500Y1491000D03*
X775000Y1495500D03*
X770551Y1513685D03*
X773528Y1510662D03*
Y1505662D03*
Y1500662D03*
X786803Y1490063D03*
X791803D03*
X796803D03*
X801803D03*
X806803D03*
X811803D03*
X816803D03*
X821803D03*
X826803D03*
X831803D03*
X836803D03*
X841803D03*
X846803D03*
X851803D03*
X856803D03*
X861803D03*
X887127Y254031D03*
X866803Y1490063D03*
X871803D03*
X876803D03*
X881803D03*
X886803D03*
X891803D03*
X896803D03*
X901803D03*
X906803D03*
X911803D03*
X916803D03*
X921803D03*
X926803D03*
X931803D03*
X936803D03*
X941803D03*
X946803D03*
X951803D03*
X956803D03*
X997000Y1496000D03*
X993000Y1491500D03*
X961803Y1490063D03*
X966803D03*
X971803D03*
X976803D03*
X981803D03*
X986803D03*
X998126Y1503614D03*
Y1508614D03*
Y1513614D03*
X1003126D03*
X1008126D03*
X1013126D03*
X1018126D03*
X1023126D03*
X1028126D03*
X1033126D03*
X1038126D03*
X1043126D03*
X1048126D03*
X1053126D03*
X1068734Y195764D03*
X1064500Y197500D03*
X1065055Y201895D03*
Y206895D03*
Y211895D03*
Y216895D03*
Y226895D03*
Y231895D03*
Y236895D03*
Y241895D03*
Y221895D03*
X1148734Y195764D03*
X1143734D03*
X1138734D03*
X1133734D03*
X1128734D03*
X1123734D03*
X1118734D03*
X1113734D03*
X1103734D03*
X1098734D03*
X1093734D03*
X1088734D03*
X1083734D03*
X1078734D03*
X1073734D03*
X1075627Y374973D03*
X1075829Y380885D03*
X1076142Y386839D03*
X1087933Y1411323D03*
X1082933D03*
X1077933D03*
X1095567Y1426057D03*
X1058126Y1513614D03*
X1061675Y1510352D03*
X1065210Y1506817D03*
X1066638Y1472408D03*
Y1467408D03*
Y1462408D03*
Y1457408D03*
Y1452408D03*
Y1447408D03*
Y1442408D03*
X1095567Y1431057D03*
Y1436057D03*
Y1441057D03*
Y1446057D03*
Y1451057D03*
Y1456057D03*
Y1461057D03*
Y1466057D03*
X1096039Y1505861D03*
X1099575Y1509397D03*
X1103110Y1512932D03*
X1107798Y1513685D03*
X1112798D03*
X1117798D03*
X1122798D03*
X1127798D03*
X1132798D03*
X1137798D03*
X1142798D03*
X1147798D03*
X1095567Y1471057D03*
X1066638Y1502408D03*
X1115000Y1485000D03*
X1118000Y1480500D03*
X1112000D03*
X1234500Y6000D03*
X1243844D03*
X1238844D03*
X1230409Y7565D03*
Y12565D03*
Y17565D03*
Y22565D03*
Y27565D03*
Y32565D03*
Y37565D03*
Y42565D03*
Y47565D03*
Y52565D03*
Y57565D03*
Y62565D03*
Y67565D03*
Y72565D03*
Y77565D03*
Y82565D03*
Y87565D03*
Y92565D03*
X1229000Y189500D03*
X1230409Y97565D03*
Y102565D03*
Y107565D03*
Y112565D03*
Y117565D03*
Y122565D03*
Y127565D03*
Y132565D03*
Y137565D03*
Y142565D03*
Y147565D03*
Y152565D03*
Y157565D03*
Y162565D03*
Y167565D03*
Y172565D03*
Y177565D03*
Y182565D03*
X1225000Y194000D03*
X1218734Y195764D03*
X1213734D03*
X1208734D03*
X1203734D03*
X1198734D03*
X1193734D03*
X1188734D03*
X1183734D03*
X1178734D03*
X1173734D03*
X1168734D03*
X1163734D03*
X1158734D03*
X1153734D03*
X1245500Y1500500D03*
X1208000Y1502500D03*
X1234783Y1499118D03*
X1229783D03*
X1224783D03*
X1219783D03*
X1214783D03*
X1239783D03*
X1152798Y1513685D03*
X1157798D03*
X1162798D03*
X1167798D03*
X1172798D03*
X1177798D03*
X1182798D03*
X1187798D03*
X1192798D03*
X1197798D03*
X1202798D03*
X1205500Y1509000D03*
X1338844Y6000D03*
X1333844D03*
X1328844D03*
X1323844D03*
X1318844D03*
X1313844D03*
X1308844D03*
X1303844D03*
X1298844D03*
X1293844D03*
X1288844D03*
X1283844D03*
X1278844D03*
X1273844D03*
X1268844D03*
X1263844D03*
X1258844D03*
X1253844D03*
X1248844D03*
X1249000Y1504500D03*
X1328464Y1513685D03*
X1333464D03*
X1338464D03*
X1293464D03*
X1298464D03*
X1303464D03*
X1308464D03*
X1313464D03*
X1318464D03*
X1323464D03*
X1250500Y1510500D03*
X1253464Y1513685D03*
X1258464D03*
X1263464D03*
X1268464D03*
X1273464D03*
X1278464D03*
X1283464D03*
X1288464D03*
X1433844Y6000D03*
X1428844D03*
X1423844D03*
X1418844D03*
X1413844D03*
X1408844D03*
X1403844D03*
X1398844D03*
X1393844D03*
X1388844D03*
X1383844D03*
X1378844D03*
X1373844D03*
X1368844D03*
X1363844D03*
X1358844D03*
X1353844D03*
X1348844D03*
X1343844D03*
X1433500Y1490500D03*
X1428500Y1494000D03*
X1403500Y1513500D03*
X1398500D03*
X1363464Y1513685D03*
X1368464D03*
X1373464D03*
X1378464D03*
X1383464D03*
X1388464D03*
X1393464D03*
X1353464D03*
X1358464D03*
X1343464D03*
X1348464D03*
X1408464D03*
X1413464D03*
X1418464D03*
X1423464D03*
X1425890Y1510111D03*
Y1505111D03*
Y1500111D03*
X1528844Y6000D03*
X1523844D03*
X1518844D03*
X1513844D03*
X1508844D03*
X1503844D03*
X1498844D03*
X1493844D03*
X1488844D03*
X1483844D03*
X1478844D03*
X1473844D03*
X1468844D03*
X1463844D03*
X1458844D03*
X1453844D03*
X1448844D03*
X1443844D03*
X1438844D03*
X1439716Y1490063D03*
X1444716D03*
X1449716D03*
X1454716D03*
X1459716D03*
X1464716D03*
X1469716D03*
X1474716D03*
X1479716D03*
X1484716D03*
X1489716D03*
X1494716D03*
X1499716D03*
X1504716D03*
X1509716D03*
X1514716D03*
X1519716D03*
X1524716D03*
X1529716D03*
X1623844Y6000D03*
X1618844D03*
X1613844D03*
X1608844D03*
X1603844D03*
X1598844D03*
X1593844D03*
X1588844D03*
X1583844D03*
X1578844D03*
X1573844D03*
X1568844D03*
X1563844D03*
X1558844D03*
X1553844D03*
X1548844D03*
X1543844D03*
X1538844D03*
X1533844D03*
X1534716Y1490063D03*
X1539716D03*
X1544716D03*
X1549716D03*
X1554716D03*
X1559716D03*
X1564716D03*
X1569716D03*
X1574716D03*
X1579716D03*
X1584716D03*
X1589716D03*
X1594716D03*
X1599716D03*
X1604716D03*
X1609716D03*
X1614716D03*
X1619716D03*
X1624716D03*
X1718844Y6000D03*
X1713844D03*
X1708844D03*
X1703844D03*
X1698844D03*
X1693844D03*
X1688844D03*
X1683844D03*
X1678844D03*
X1673844D03*
X1668844D03*
X1663844D03*
X1658844D03*
X1653844D03*
X1648844D03*
X1643844D03*
X1638844D03*
X1633844D03*
X1628844D03*
X1649500Y1497500D03*
X1646000Y1492000D03*
X1720968Y1513685D03*
X1715968D03*
X1710968D03*
X1705968D03*
X1700968D03*
X1695968D03*
X1690968D03*
X1685968D03*
X1680968D03*
X1670968D03*
X1675968D03*
X1629716Y1490063D03*
X1634716D03*
X1639716D03*
X1650488Y1504165D03*
Y1509165D03*
X1650968Y1513685D03*
X1655968D03*
X1660968D03*
X1665968D03*
X1813844Y6000D03*
X1808844D03*
X1803844D03*
X1798844D03*
X1793844D03*
X1788844D03*
X1783844D03*
X1778844D03*
X1773844D03*
X1768844D03*
X1763844D03*
X1758844D03*
X1753844D03*
X1748844D03*
X1743844D03*
X1738844D03*
X1733844D03*
X1728844D03*
X1723844D03*
X1786004Y1513500D03*
X1780968Y1513685D03*
X1775968D03*
X1770968D03*
X1765968D03*
X1760968D03*
X1755968D03*
X1750968D03*
X1745968D03*
X1740968D03*
X1796004Y1513500D03*
X1801004D03*
X1806004D03*
X1811004D03*
X1816004D03*
X1730968Y1513685D03*
X1725968D03*
X1791004Y1513500D03*
X1735968Y1513685D03*
X1913844Y6000D03*
X1908844D03*
X1903844D03*
X1898844D03*
X1893844D03*
X1888844D03*
X1883844D03*
X1878844D03*
X1873844D03*
X1868844D03*
X1863844D03*
X1858844D03*
X1853844D03*
X1848844D03*
X1843844D03*
X1838844D03*
X1833844D03*
X1828844D03*
X1823844D03*
X1818844D03*
X1869500Y1503500D03*
X1865500Y1500000D03*
X1829500Y1501500D03*
X1826500Y1506500D03*
X1855256Y1499118D03*
X1850256D03*
X1845256D03*
X1840256D03*
X1826040Y1513315D03*
X1821040D03*
X1835256Y1499118D03*
X1860256D03*
X1871157Y1509110D03*
X1871582Y1513685D03*
X1876582D03*
X1881582D03*
X1886582D03*
X1891582D03*
X1896582D03*
X1901582D03*
X1906582D03*
X1911582D03*
X1928843Y8985D03*
Y93985D03*
Y88985D03*
Y83985D03*
Y78985D03*
Y73985D03*
Y68985D03*
Y63985D03*
Y58985D03*
Y53985D03*
Y48985D03*
Y43985D03*
Y38985D03*
Y28985D03*
Y23985D03*
Y18985D03*
Y13985D03*
Y33985D03*
X1923844Y6000D03*
X1918844D03*
X1928843Y98985D03*
Y188985D03*
Y183985D03*
Y178985D03*
Y173985D03*
Y168985D03*
Y163985D03*
Y158985D03*
Y153985D03*
Y148985D03*
Y143985D03*
Y138985D03*
Y133985D03*
Y128985D03*
Y123985D03*
Y118985D03*
Y113985D03*
Y108985D03*
Y103985D03*
Y283985D03*
Y278985D03*
Y273985D03*
Y268985D03*
Y263985D03*
Y258985D03*
Y253985D03*
Y248985D03*
Y243985D03*
Y238985D03*
Y233985D03*
Y228985D03*
Y223985D03*
Y218985D03*
Y213985D03*
Y208985D03*
Y203985D03*
Y198985D03*
Y193985D03*
Y378985D03*
Y373985D03*
Y368985D03*
Y363985D03*
Y358985D03*
Y353985D03*
Y348985D03*
Y343985D03*
Y338985D03*
Y333985D03*
Y328985D03*
Y323985D03*
Y318985D03*
Y313985D03*
Y308985D03*
Y303985D03*
Y298985D03*
Y293985D03*
Y288985D03*
Y418985D03*
Y433985D03*
Y428985D03*
Y423985D03*
Y473985D03*
Y468985D03*
Y463985D03*
Y458985D03*
Y453985D03*
Y448985D03*
Y443985D03*
Y438985D03*
Y413985D03*
Y408985D03*
Y403985D03*
Y398985D03*
Y393985D03*
Y388985D03*
Y383985D03*
Y568985D03*
Y563985D03*
Y558985D03*
Y553985D03*
Y548985D03*
Y543985D03*
Y538985D03*
Y533985D03*
Y528985D03*
Y523985D03*
Y518985D03*
Y513985D03*
Y508985D03*
Y503985D03*
Y498985D03*
Y493985D03*
Y488985D03*
Y483985D03*
Y478985D03*
Y663985D03*
Y658985D03*
Y653985D03*
Y648985D03*
Y643985D03*
Y638985D03*
Y633985D03*
Y628985D03*
Y623985D03*
Y618985D03*
Y613985D03*
Y608985D03*
Y603985D03*
Y598985D03*
Y593985D03*
Y588985D03*
Y583985D03*
Y578985D03*
Y573985D03*
Y758985D03*
Y753985D03*
Y748985D03*
Y743985D03*
Y738985D03*
Y733985D03*
Y728985D03*
Y723985D03*
Y718985D03*
Y713985D03*
Y708985D03*
Y703985D03*
Y698985D03*
Y693985D03*
Y688985D03*
Y683985D03*
Y678985D03*
Y673985D03*
Y668985D03*
Y853985D03*
Y848985D03*
Y843985D03*
Y838985D03*
Y833985D03*
Y828985D03*
Y823985D03*
Y818985D03*
Y813985D03*
Y808985D03*
Y803985D03*
Y798985D03*
Y793985D03*
Y788985D03*
Y783985D03*
Y778985D03*
Y773985D03*
Y768985D03*
Y763985D03*
Y918985D03*
Y913985D03*
Y908985D03*
Y903985D03*
Y898985D03*
Y893985D03*
Y888985D03*
Y883985D03*
Y878985D03*
Y873985D03*
Y868985D03*
Y863985D03*
Y858985D03*
Y948985D03*
Y943985D03*
Y938985D03*
Y933985D03*
Y928985D03*
Y923985D03*
Y1043985D03*
Y1038985D03*
Y1033985D03*
Y1028985D03*
Y1023985D03*
Y1018985D03*
Y1013985D03*
Y1008985D03*
Y1003985D03*
Y998985D03*
Y993985D03*
Y988985D03*
Y983985D03*
Y978985D03*
Y973985D03*
Y968985D03*
Y963985D03*
Y958985D03*
Y953985D03*
Y1143985D03*
Y1138985D03*
Y1133985D03*
Y1128985D03*
Y1123985D03*
Y1118985D03*
Y1113985D03*
Y1108985D03*
Y1103985D03*
Y1098985D03*
Y1093985D03*
Y1088985D03*
Y1083985D03*
Y1078985D03*
Y1073985D03*
Y1068985D03*
Y1063985D03*
Y1058985D03*
Y1053985D03*
Y1048985D03*
Y1238985D03*
Y1233985D03*
Y1228985D03*
Y1223985D03*
Y1218985D03*
Y1213985D03*
Y1208985D03*
Y1203985D03*
Y1198985D03*
Y1193985D03*
Y1188985D03*
Y1183985D03*
Y1178985D03*
Y1173985D03*
Y1168985D03*
Y1163985D03*
Y1158985D03*
Y1153985D03*
Y1148985D03*
Y1288985D03*
Y1293985D03*
Y1298985D03*
Y1303985D03*
Y1308985D03*
Y1313985D03*
Y1318985D03*
Y1323985D03*
Y1328985D03*
Y1333985D03*
Y1283985D03*
Y1278985D03*
Y1273985D03*
Y1268985D03*
Y1263985D03*
Y1258985D03*
Y1253985D03*
Y1248985D03*
Y1243985D03*
Y1348985D03*
Y1353985D03*
Y1358985D03*
Y1363985D03*
Y1368985D03*
Y1373985D03*
Y1378985D03*
Y1383985D03*
Y1388985D03*
Y1393985D03*
Y1398985D03*
Y1403985D03*
Y1408985D03*
Y1413985D03*
Y1418985D03*
Y1423985D03*
Y1428985D03*
Y1338985D03*
Y1343985D03*
Y1448985D03*
Y1443985D03*
Y1433985D03*
Y1438985D03*
X1920000Y1458000D03*
X1917500Y1463500D03*
X1916582Y1513685D03*
X1917031Y1509134D03*
Y1504134D03*
Y1499134D03*
Y1494134D03*
Y1489134D03*
Y1484134D03*
Y1479134D03*
Y1474134D03*
Y1469134D03*
X1926500Y1455000D03*
G54D20*
G01X489037Y-206331D02*
X489911Y-205456D01*
X490566Y-203998D01*
X491003Y-201955D01*
X490566Y-200206D01*
X489693Y-199039D01*
X488164Y-198164D01*
X482269D01*
Y-215664D01*
X489474D01*
X491003Y-214498D01*
X491876Y-212747D01*
X492313Y-210706D01*
X491876Y-208664D01*
X490566Y-206914D01*
X489037Y-206331D01*
X482269D01*
G01X501734Y-215664D02*
Y-203998D01*
G01Y-206331D02*
X502826Y-205164D01*
X503918Y-204289D01*
X505446Y-203998D01*
X506537Y-204289D01*
X507848Y-205164D01*
G01X517706Y-220914D02*
X519016Y-221497D01*
X520763Y-220914D01*
X521854Y-219748D01*
X522728Y-218289D01*
X524037Y-213623D01*
X526876Y-203998D01*
G01X519889D02*
X524037Y-213623D01*
G01X543284Y-205456D02*
X541756Y-204289D01*
X540446Y-203998D01*
X538699Y-204581D01*
X537389Y-205747D01*
X536516Y-207789D01*
X536297Y-209831D01*
X536516Y-211873D01*
X537389Y-213623D01*
X538699Y-215081D01*
X540446Y-215664D01*
X541974Y-215081D01*
X543284Y-213914D01*
G01X554016Y-207789D02*
X561003D01*
X560348Y-205747D01*
X559256Y-204581D01*
X557728Y-203998D01*
X556199Y-204289D01*
X554889Y-205164D01*
X554016Y-207206D01*
X553579Y-208956D01*
Y-210706D01*
X554016Y-212456D01*
X555108Y-214206D01*
X556418Y-215372D01*
X557946Y-215664D01*
X559474Y-215081D01*
X561003Y-213331D01*
G01X597094Y-199623D02*
X595784Y-198747D01*
X594256Y-198164D01*
X592509D01*
X590544Y-199039D01*
X589016Y-200497D01*
X587924Y-202248D01*
X587051Y-205164D01*
X586832Y-207789D01*
X587269Y-210414D01*
X587924Y-212164D01*
X589234Y-213914D01*
X590763Y-215081D01*
X592291Y-215664D01*
X593819D01*
X595348Y-215081D01*
X596658Y-214206D01*
X597750Y-213040D01*
G01X613721Y-215664D02*
Y-203998D01*
G01Y-206039D02*
X612848Y-204873D01*
X611537Y-204289D01*
X610009Y-203998D01*
X608481Y-204581D01*
X607171Y-205747D01*
X606297Y-207497D01*
X605861Y-209831D01*
X606297Y-212164D01*
X607171Y-213914D01*
X608481Y-215081D01*
X610009Y-215664D01*
X611537Y-215372D01*
X612848Y-214498D01*
X613721Y-213331D01*
G01X623579Y-215664D02*
Y-203998D01*
G01Y-206914D02*
X624453Y-205456D01*
X625763Y-204289D01*
X627509Y-203998D01*
X629037Y-204289D01*
X630348Y-205456D01*
X631003Y-207497D01*
Y-215664D01*
G01X640206Y-220914D02*
X641516Y-221497D01*
X643263Y-220914D01*
X644354Y-219748D01*
X645228Y-218289D01*
X646537Y-213623D01*
X649376Y-203998D01*
G01X642389D02*
X646537Y-213623D01*
G01X662291Y-215664D02*
X660981Y-215372D01*
X659671Y-214206D01*
X658797Y-212164D01*
X658361Y-209831D01*
X658797Y-207497D01*
X659671Y-205456D01*
X660981Y-204289D01*
X662291Y-203998D01*
X663601Y-204289D01*
X664911Y-205456D01*
X665784Y-207497D01*
X666003Y-209831D01*
X665784Y-212164D01*
X664911Y-214206D01*
X663601Y-215372D01*
X662291Y-215664D01*
G01X676079D02*
Y-203998D01*
G01Y-206914D02*
X676953Y-205456D01*
X678263Y-204289D01*
X680009Y-203998D01*
X681537Y-204289D01*
X682848Y-205456D01*
X683503Y-207497D01*
Y-215664D01*
G01X710424D02*
Y-198164D01*
X715883D01*
X717629Y-199039D01*
X718721Y-200206D01*
X719158Y-202539D01*
X718721Y-204873D01*
X717411Y-206331D01*
X715883Y-207206D01*
X710424D01*
G01X715883D02*
X719158Y-215664D01*
G01X732291Y-216247D02*
X731854Y-215956D01*
Y-215372D01*
X732291Y-215081D01*
X732728Y-215372D01*
Y-215956D01*
X732291Y-216247D01*
G01X744988Y-215664D02*
Y-198164D01*
X749354D01*
X751101Y-199039D01*
X752411Y-200206D01*
X753503Y-201955D01*
X754376Y-203998D01*
X754594Y-206914D01*
X754376Y-209831D01*
X753503Y-211873D01*
X752411Y-213623D01*
X751101Y-214789D01*
X749354Y-215664D01*
X744988D01*
G01X762924D02*
Y-198164D01*
X768164D01*
X769911Y-199039D01*
X771221Y-201081D01*
X771658Y-203414D01*
X771221Y-205747D01*
X770129Y-207497D01*
X768164Y-208373D01*
X762924D01*
G01X786537Y-206331D02*
X787411Y-205456D01*
X788066Y-203998D01*
X788503Y-201955D01*
X788066Y-200206D01*
X787193Y-199039D01*
X785664Y-198164D01*
X779769D01*
Y-215664D01*
X786974D01*
X788503Y-214498D01*
X789376Y-212747D01*
X789813Y-210706D01*
X789376Y-208664D01*
X788066Y-206914D01*
X786537Y-206331D01*
X779769D01*
G01X595364Y-170664D02*
Y-153164D01*
X601041Y-167747D01*
X606718Y-153164D01*
Y-170664D01*
G01X618541D02*
X617231Y-170372D01*
X615921Y-169206D01*
X615047Y-167164D01*
X614611Y-164831D01*
X615047Y-162497D01*
X615921Y-160456D01*
X617231Y-159289D01*
X618541Y-158998D01*
X619851Y-159289D01*
X621161Y-160456D01*
X622034Y-162497D01*
X622253Y-164831D01*
X622034Y-167164D01*
X621161Y-169206D01*
X619851Y-170372D01*
X618541Y-170664D01*
G01X639971Y-153164D02*
Y-170664D01*
G01Y-168040D02*
X639098Y-169498D01*
X637787Y-170372D01*
X636259Y-170664D01*
X634513Y-170081D01*
X633203Y-168623D01*
X632329Y-166873D01*
X632111Y-164831D01*
X632329Y-162789D01*
X633203Y-161039D01*
X634513Y-159581D01*
X636259Y-158998D01*
X637787Y-159289D01*
X638879Y-159873D01*
X639971Y-161039D01*
G01X650266Y-162789D02*
X657253D01*
X656598Y-160747D01*
X655506Y-159581D01*
X653978Y-158998D01*
X652449Y-159289D01*
X651139Y-160164D01*
X650266Y-162206D01*
X649829Y-163956D01*
Y-165706D01*
X650266Y-167456D01*
X651358Y-169206D01*
X652668Y-170372D01*
X654196Y-170664D01*
X655724Y-170081D01*
X657253Y-168331D01*
G01X671041Y-170664D02*
Y-153164D01*
G01X839441Y-215664D02*
Y-198164D01*
X836821Y-201664D01*
G01Y-215664D02*
X842061D01*
G01X852793Y-208373D02*
X854321Y-206331D01*
X855631Y-205164D01*
X857378Y-204581D01*
X858906Y-205164D01*
X859998Y-206331D01*
X860871Y-208081D01*
X861089Y-210122D01*
X860871Y-211873D01*
X859998Y-213623D01*
X858687Y-215081D01*
X857159Y-215664D01*
X855413Y-215081D01*
X853884Y-213331D01*
X853011Y-210706D01*
X852793Y-207789D01*
X853229Y-203998D01*
X853884Y-201955D01*
X854976Y-199914D01*
X856504Y-198456D01*
X858033Y-198164D01*
X859561Y-198747D01*
X860653Y-200206D01*
G01X869638Y-212164D02*
X870947Y-214206D01*
X872694Y-215372D01*
X874659Y-215664D01*
X876406Y-215372D01*
X878153Y-213914D01*
X879244Y-212164D01*
X879463Y-210414D01*
X879026Y-208373D01*
X877498Y-206914D01*
X875969Y-206331D01*
X874004D01*
G01X875969D02*
X877279Y-205456D01*
X878371Y-203998D01*
X878808Y-202248D01*
X878371Y-200497D01*
X877279Y-199039D01*
X875314Y-198164D01*
X873349Y-198456D01*
X871384Y-199623D01*
G01X891941Y-215664D02*
Y-198164D01*
X889321Y-201664D01*
G01Y-215664D02*
X894561D01*
G01X909004D02*
X909441Y-211873D01*
X910096Y-208664D01*
X910969Y-205747D01*
X912061Y-202539D01*
X913808Y-198164D01*
X905074D01*
G01X826324Y-170664D02*
Y-153164D01*
X831564D01*
X833311Y-154039D01*
X834621Y-156081D01*
X835058Y-158414D01*
X834621Y-160747D01*
X833529Y-162497D01*
X831564Y-163373D01*
X826324D01*
G01X852994Y-154623D02*
X851684Y-153747D01*
X850156Y-153164D01*
X848409D01*
X846444Y-154039D01*
X844916Y-155497D01*
X843824Y-157248D01*
X842951Y-160164D01*
X842732Y-162789D01*
X843169Y-165414D01*
X843824Y-167164D01*
X845134Y-168914D01*
X846663Y-170081D01*
X848191Y-170664D01*
X849719D01*
X851248Y-170081D01*
X852558Y-169206D01*
X853650Y-168040D01*
G01X867437Y-161331D02*
X868311Y-160456D01*
X868966Y-158998D01*
X869403Y-156955D01*
X868966Y-155206D01*
X868093Y-154039D01*
X866564Y-153164D01*
X860669D01*
Y-170664D01*
X867874D01*
X869403Y-169498D01*
X870276Y-167747D01*
X870713Y-165706D01*
X870276Y-163664D01*
X868966Y-161914D01*
X867437Y-161331D01*
X860669D01*
G01X876641Y-176497D02*
X889741D01*
G01X895669Y-170664D02*
Y-153164D01*
X905713Y-170664D01*
Y-153164D01*
G01X918191Y-170664D02*
X916444Y-170372D01*
X914916Y-169206D01*
X913606Y-167456D01*
X912732Y-165414D01*
X912296Y-163081D01*
Y-160747D01*
X912732Y-158414D01*
X913606Y-156372D01*
X914916Y-154623D01*
X916444Y-153456D01*
X918191Y-153164D01*
X919937Y-153456D01*
X921466Y-154623D01*
X922776Y-156372D01*
X923650Y-158414D01*
X924086Y-160747D01*
Y-163081D01*
X923650Y-165414D01*
X922776Y-167456D01*
X921466Y-169206D01*
X919937Y-170372D01*
X918191Y-170664D01*
G01X1000741Y-215664D02*
Y-198164D01*
X998121Y-201664D01*
G01Y-215664D02*
X1003361D01*
G01X969032Y-153164D02*
X974491Y-170664D01*
X979950Y-153164D01*
G01X996358Y-170664D02*
X987624D01*
Y-153164D01*
X996358D01*
G01X992864Y-161622D02*
X987624D01*
G01X1005124Y-170664D02*
Y-153164D01*
X1010583D01*
X1012329Y-154039D01*
X1013421Y-155206D01*
X1013858Y-157539D01*
X1013421Y-159873D01*
X1012111Y-161331D01*
X1010583Y-162206D01*
X1005124D01*
G01X1010583D02*
X1013858Y-170664D01*
G01X1026991Y-171247D02*
X1026554Y-170956D01*
Y-170372D01*
X1026991Y-170081D01*
X1027428Y-170372D01*
Y-170956D01*
X1026991Y-171247D01*
G01X1155058Y-198164D02*
Y-215664D01*
X1146324D01*
G01X1137339Y-208373D02*
X1135811Y-206331D01*
X1134501Y-205164D01*
X1132754Y-204581D01*
X1131226Y-205164D01*
X1130134Y-206331D01*
X1129261Y-208081D01*
X1129043Y-210122D01*
X1129261Y-211873D01*
X1130134Y-213623D01*
X1131445Y-215081D01*
X1132973Y-215664D01*
X1134719Y-215081D01*
X1136248Y-213331D01*
X1137121Y-210706D01*
X1137339Y-207789D01*
X1136903Y-203998D01*
X1136248Y-201955D01*
X1135156Y-199914D01*
X1133628Y-198456D01*
X1132099Y-198164D01*
X1130571Y-198747D01*
X1129479Y-200206D01*
G01X1102574Y-153164D02*
Y-170664D01*
X1111308D01*
G01X1128371D02*
Y-158998D01*
G01Y-161039D02*
X1127498Y-159873D01*
X1126187Y-159289D01*
X1124659Y-158998D01*
X1123131Y-159581D01*
X1121821Y-160747D01*
X1120947Y-162497D01*
X1120511Y-164831D01*
X1120947Y-167164D01*
X1121821Y-168914D01*
X1123131Y-170081D01*
X1124659Y-170664D01*
X1126187Y-170372D01*
X1127498Y-169498D01*
X1128371Y-168331D01*
G01X1137356Y-175914D02*
X1138666Y-176497D01*
X1140413Y-175914D01*
X1141504Y-174748D01*
X1142378Y-173289D01*
X1143687Y-168623D01*
X1146526Y-158998D01*
G01X1139539D02*
X1143687Y-168623D01*
G01X1156166Y-162789D02*
X1163153D01*
X1162498Y-160747D01*
X1161406Y-159581D01*
X1159878Y-158998D01*
X1158349Y-159289D01*
X1157039Y-160164D01*
X1156166Y-162206D01*
X1155729Y-163956D01*
Y-165706D01*
X1156166Y-167456D01*
X1157258Y-169206D01*
X1158568Y-170372D01*
X1160096Y-170664D01*
X1161624Y-170081D01*
X1163153Y-168331D01*
G01X1173884Y-170664D02*
Y-158998D01*
G01Y-161331D02*
X1174976Y-160164D01*
X1176068Y-159289D01*
X1177596Y-158998D01*
X1178687Y-159289D01*
X1179998Y-160164D01*
G01X1244688Y-170664D02*
Y-153164D01*
X1249054D01*
X1250801Y-154039D01*
X1252111Y-155206D01*
X1253203Y-156955D01*
X1254076Y-158998D01*
X1254294Y-161914D01*
X1254076Y-164831D01*
X1253203Y-166873D01*
X1252111Y-168623D01*
X1250801Y-169789D01*
X1249054Y-170664D01*
X1244688D01*
G01X1263716Y-162789D02*
X1270703D01*
X1270048Y-160747D01*
X1268956Y-159581D01*
X1267428Y-158998D01*
X1265899Y-159289D01*
X1264589Y-160164D01*
X1263716Y-162206D01*
X1263279Y-163956D01*
Y-165706D01*
X1263716Y-167456D01*
X1264808Y-169206D01*
X1266118Y-170372D01*
X1267646Y-170664D01*
X1269174Y-170081D01*
X1270703Y-168331D01*
G01X1281216Y-168623D02*
X1282308Y-169789D01*
X1283836Y-170664D01*
X1285146D01*
X1286456Y-170081D01*
X1287329Y-169206D01*
X1287766Y-168040D01*
X1287548Y-166289D01*
X1286674Y-165414D01*
X1282744Y-163664D01*
X1281871Y-161622D01*
X1282308Y-160164D01*
X1283181Y-159289D01*
X1284491Y-158998D01*
X1285801Y-159289D01*
X1287111Y-160164D01*
G01X1301991Y-158998D02*
Y-170664D01*
G01Y-154331D02*
X1301554Y-154039D01*
Y-153456D01*
X1301991Y-153164D01*
X1302428Y-153456D01*
Y-154039D01*
X1301991Y-154331D01*
G01X1316434Y-175039D02*
X1317963Y-176206D01*
X1319709Y-176497D01*
X1321237Y-176206D01*
X1322548Y-174748D01*
X1323421Y-172706D01*
Y-158998D01*
G01Y-161331D02*
X1322548Y-160164D01*
X1321237Y-159289D01*
X1319709Y-158998D01*
X1317963Y-159581D01*
X1316871Y-160747D01*
X1315997Y-162789D01*
X1315561Y-164831D01*
X1315779Y-166581D01*
X1316653Y-168623D01*
X1317963Y-170081D01*
X1319709Y-170664D01*
X1321019Y-170372D01*
X1322548Y-169206D01*
X1323421Y-168040D01*
G01X1333279Y-170664D02*
Y-158998D01*
G01Y-161914D02*
X1334153Y-160456D01*
X1335463Y-159289D01*
X1337209Y-158998D01*
X1338737Y-159289D01*
X1340048Y-160456D01*
X1340703Y-162497D01*
Y-170664D01*
G01X1351216Y-162789D02*
X1358203D01*
X1357548Y-160747D01*
X1356456Y-159581D01*
X1354928Y-158998D01*
X1353399Y-159289D01*
X1352089Y-160164D01*
X1351216Y-162206D01*
X1350779Y-163956D01*
Y-165706D01*
X1351216Y-167456D01*
X1352308Y-169206D01*
X1353618Y-170372D01*
X1355146Y-170664D01*
X1356674Y-170081D01*
X1358203Y-168331D01*
G01X1368934Y-170664D02*
Y-158998D01*
G01Y-161331D02*
X1370026Y-160164D01*
X1371118Y-159289D01*
X1372646Y-158998D01*
X1373737Y-159289D01*
X1375048Y-160164D01*
G01X1266991Y-215664D02*
X1265244Y-215372D01*
X1263716Y-214206D01*
X1262406Y-212456D01*
X1261532Y-210414D01*
X1261096Y-208081D01*
Y-205747D01*
X1261532Y-203414D01*
X1262406Y-201372D01*
X1263716Y-199623D01*
X1265244Y-198456D01*
X1266991Y-198164D01*
X1268737Y-198456D01*
X1270266Y-199623D01*
X1271576Y-201372D01*
X1272450Y-203414D01*
X1272886Y-205747D01*
Y-208081D01*
X1272450Y-210414D01*
X1271576Y-212456D01*
X1270266Y-214206D01*
X1268737Y-215372D01*
X1266991Y-215664D01*
G01X1268737Y-210997D02*
X1271358Y-215664D01*
G01X1279688Y-198164D02*
Y-210706D01*
X1280561Y-213331D01*
X1282308Y-215081D01*
X1284491Y-215664D01*
X1286674Y-215081D01*
X1288421Y-213331D01*
X1289294Y-210706D01*
Y-198164D01*
G01X1299371D02*
X1304611D01*
G01X1301991D02*
Y-215664D01*
G01X1299371D02*
X1304611D01*
G01X1314469D02*
Y-198164D01*
X1324513Y-215664D01*
Y-198164D01*
G01X1341794Y-199623D02*
X1340484Y-198747D01*
X1338956Y-198164D01*
X1337209D01*
X1335244Y-199039D01*
X1333716Y-200497D01*
X1332624Y-202248D01*
X1331751Y-205164D01*
X1331532Y-207789D01*
X1331969Y-210414D01*
X1332624Y-212164D01*
X1333934Y-213914D01*
X1335463Y-215081D01*
X1336991Y-215664D01*
X1338519D01*
X1340048Y-215081D01*
X1341358Y-214206D01*
X1342450Y-213040D01*
G01X1354491Y-215664D02*
Y-207789D01*
X1350124Y-198164D01*
G01X1358858D02*
X1354491Y-207789D01*
G01X1415691Y-198164D02*
X1413944Y-198747D01*
X1412634Y-200206D01*
X1411761Y-201955D01*
X1411106Y-204289D01*
X1410888Y-206914D01*
X1411106Y-209539D01*
X1411761Y-211873D01*
X1412634Y-213623D01*
X1413944Y-215081D01*
X1415691Y-215664D01*
X1417437Y-215081D01*
X1418748Y-213623D01*
X1419621Y-211873D01*
X1420276Y-209539D01*
X1420494Y-206914D01*
X1420276Y-204289D01*
X1419621Y-201955D01*
X1418748Y-200206D01*
X1417437Y-198747D01*
X1415691Y-198164D01*
G01X1429043Y-208373D02*
X1430571Y-206331D01*
X1431881Y-205164D01*
X1433628Y-204581D01*
X1435156Y-205164D01*
X1436248Y-206331D01*
X1437121Y-208081D01*
X1437339Y-210122D01*
X1437121Y-211873D01*
X1436248Y-213623D01*
X1434937Y-215081D01*
X1433409Y-215664D01*
X1431663Y-215081D01*
X1430134Y-213331D01*
X1429261Y-210706D01*
X1429043Y-207789D01*
X1429479Y-203998D01*
X1430134Y-201955D01*
X1431226Y-199914D01*
X1432754Y-198456D01*
X1434283Y-198164D01*
X1435811Y-198747D01*
X1436903Y-200206D01*
G01X1446761Y-216247D02*
X1454621Y-198164D01*
G01X1468191D02*
X1466444Y-198747D01*
X1465134Y-200206D01*
X1464261Y-201955D01*
X1463606Y-204289D01*
X1463388Y-206914D01*
X1463606Y-209539D01*
X1464261Y-211873D01*
X1465134Y-213623D01*
X1466444Y-215081D01*
X1468191Y-215664D01*
X1469937Y-215081D01*
X1471248Y-213623D01*
X1472121Y-211873D01*
X1472776Y-209539D01*
X1472994Y-206914D01*
X1472776Y-204289D01*
X1472121Y-201955D01*
X1471248Y-200206D01*
X1469937Y-198747D01*
X1468191Y-198164D01*
G01X1481979Y-213623D02*
X1483508Y-215081D01*
X1485254Y-215664D01*
X1487001Y-215081D01*
X1488529Y-213331D01*
X1489621Y-210706D01*
X1490058Y-208081D01*
Y-204873D01*
X1489621Y-202248D01*
X1488529Y-199914D01*
X1487219Y-198747D01*
X1485691Y-198164D01*
X1483944Y-198747D01*
X1482634Y-199914D01*
X1481761Y-201664D01*
X1481324Y-203998D01*
X1481761Y-206039D01*
X1482853Y-208081D01*
X1484163Y-209248D01*
X1485691Y-209539D01*
X1487437Y-208956D01*
X1488748Y-207497D01*
X1490058Y-204873D01*
G01X1499261Y-216247D02*
X1507121Y-198164D01*
G01X1516543Y-201081D02*
X1517853Y-199331D01*
X1519381Y-198456D01*
X1521128Y-198164D01*
X1523311Y-198747D01*
X1524839Y-200206D01*
X1525276Y-201955D01*
X1525058Y-203706D01*
X1524184Y-205164D01*
X1519818Y-208081D01*
X1517853Y-210122D01*
X1516543Y-213040D01*
X1516106Y-215664D01*
X1525276D01*
G01X1538191Y-198164D02*
X1536444Y-198747D01*
X1535134Y-200206D01*
X1534261Y-201955D01*
X1533606Y-204289D01*
X1533388Y-206914D01*
X1533606Y-209539D01*
X1534261Y-211873D01*
X1535134Y-213623D01*
X1536444Y-215081D01*
X1538191Y-215664D01*
X1539937Y-215081D01*
X1541248Y-213623D01*
X1542121Y-211873D01*
X1542776Y-209539D01*
X1542994Y-206914D01*
X1542776Y-204289D01*
X1542121Y-201955D01*
X1541248Y-200206D01*
X1539937Y-198747D01*
X1538191Y-198164D01*
G01X1555691Y-215664D02*
Y-198164D01*
X1553071Y-201664D01*
G01Y-215664D02*
X1558311D01*
G01X1572754D02*
X1573191Y-211873D01*
X1573846Y-208664D01*
X1574719Y-205747D01*
X1575811Y-202539D01*
X1577558Y-198164D01*
X1568824D01*
G01X1463388Y-170664D02*
Y-153164D01*
X1467754D01*
X1469501Y-154039D01*
X1470811Y-155206D01*
X1471903Y-156955D01*
X1472776Y-158998D01*
X1472994Y-161914D01*
X1472776Y-164831D01*
X1471903Y-166873D01*
X1470811Y-168623D01*
X1469501Y-169789D01*
X1467754Y-170664D01*
X1463388D01*
G01X1489621D02*
Y-158998D01*
G01Y-161039D02*
X1488748Y-159873D01*
X1487437Y-159289D01*
X1485909Y-158998D01*
X1484381Y-159581D01*
X1483071Y-160747D01*
X1482197Y-162497D01*
X1481761Y-164831D01*
X1482197Y-167164D01*
X1483071Y-168914D01*
X1484381Y-170081D01*
X1485909Y-170664D01*
X1487437Y-170372D01*
X1488748Y-169498D01*
X1489621Y-168331D01*
G01X1503191Y-153164D02*
Y-170664D01*
G01X1500134Y-158998D02*
X1506248D01*
G01X1517416Y-162789D02*
X1524403D01*
X1523748Y-160747D01*
X1522656Y-159581D01*
X1521128Y-158998D01*
X1519599Y-159289D01*
X1518289Y-160164D01*
X1517416Y-162206D01*
X1516979Y-163956D01*
Y-165706D01*
X1517416Y-167456D01*
X1518508Y-169206D01*
X1519818Y-170372D01*
X1521346Y-170664D01*
X1522874Y-170081D01*
X1524403Y-168331D01*
G54D11*
X95800Y71800D03*
X30500Y67000D03*
X84581Y397946D03*
X79581D03*
X95500Y525500D03*
X46442Y825000D03*
X95500Y972500D03*
X185551Y21529D03*
X151200Y48500D03*
Y44400D03*
X145864Y33216D03*
X175650Y28600D03*
X169442Y824700D03*
X125500Y992500D03*
X136774Y1411000D03*
X165774Y1422700D03*
X137624Y1469000D03*
X104184Y1457200D03*
X139374Y1486100D03*
X113314Y1441700D03*
X215500Y80500D03*
X218214Y397600D03*
X213214D03*
X220000Y524000D03*
X252000Y992500D03*
X220000Y978200D03*
X340650Y69300D03*
X320514Y397600D03*
X315514D03*
X344000Y525300D03*
X294542Y825000D03*
X376000Y993000D03*
X344200Y978200D03*
X373492Y1317441D03*
Y1322441D03*
Y1327441D03*
Y1332441D03*
X343688Y1317736D03*
Y1322736D03*
Y1327736D03*
Y1332736D03*
X313688D03*
Y1327736D03*
Y1322736D03*
Y1317736D03*
Y1312736D03*
X369086Y1313208D03*
X374086D03*
X379086D03*
X384086D03*
X324086D03*
X329086D03*
X334086D03*
X339086D03*
X344086D03*
X349086D03*
X354086D03*
X359086D03*
X364086D03*
X294086D03*
X299086D03*
X304086D03*
X309086D03*
X319086D03*
X373492Y1337441D03*
Y1342441D03*
Y1347441D03*
Y1352441D03*
X343688Y1337736D03*
Y1342736D03*
Y1347736D03*
Y1352736D03*
X313688D03*
Y1347736D03*
Y1342736D03*
Y1337736D03*
X323688Y1357736D03*
X328688D03*
X333688D03*
X338688D03*
X343688D03*
X348688D03*
X353688D03*
X358688D03*
X363688D03*
X368688D03*
X373688D03*
X378688D03*
X383688D03*
X298688D03*
X303688D03*
X308688D03*
X313688D03*
X318688D03*
X293688D03*
X464000Y80500D03*
X464801Y521156D03*
X418742Y824444D03*
X468300Y978000D03*
X389086Y1313208D03*
X394086D03*
X388688Y1357736D03*
X393688D03*
X500000Y992000D03*
X503001Y1454922D03*
X589150Y69500D03*
X592500Y525300D03*
X666900Y665400D03*
X646680Y679430D03*
X582648Y825223D03*
X659642Y824700D03*
X624500Y993000D03*
X592800Y978100D03*
X646102Y1321750D03*
X641102D03*
X646200Y1420576D03*
X641200D03*
X637971Y1425400D03*
X650000Y1464052D03*
Y1467948D03*
Y1457448D03*
Y1453552D03*
X636250Y1468500D03*
X628500D03*
X637972Y1441419D03*
X709000Y79500D03*
X711352Y26875D03*
X715205Y27012D03*
X705171Y16254D03*
X714600Y498100D03*
X716400Y525200D03*
X709871Y686246D03*
X718100Y738500D03*
X718200Y744000D03*
X723000Y739200D03*
X723300Y743700D03*
X728175Y741300D03*
X728100Y745500D03*
X701700Y872700D03*
X714500Y870100D03*
X723600Y872400D03*
X727600Y872300D03*
X754000Y884524D03*
X757600Y884400D03*
X755200Y992400D03*
X716800Y978300D03*
X759249Y1008800D03*
X680900Y1469200D03*
X680200Y1465500D03*
X692000Y1471156D03*
X689250Y1433500D03*
X681250D03*
X745000Y1463000D03*
X718900Y1472800D03*
X679800Y1483500D03*
X708600Y1469900D03*
X724066Y1461018D03*
X724255Y1457253D03*
X835165Y470414D03*
X848799Y457202D03*
X849539Y453596D03*
X827313Y464805D03*
X827361Y459317D03*
X832417Y459017D03*
X808395Y454315D03*
X858740Y486430D03*
X794883Y639984D03*
X798475Y640227D03*
X860360Y605900D03*
X791530Y614700D03*
X791680Y619050D03*
X799900Y636300D03*
X807440Y629910D03*
X802900Y634000D03*
X778627Y735644D03*
X778683Y745049D03*
X778735Y839888D03*
X826000Y857400D03*
X815469Y811029D03*
X815330Y807050D03*
X858500Y845700D03*
X858100Y850000D03*
X848300Y847700D03*
X825900Y862040D03*
X815400Y892800D03*
X844800Y895902D03*
X845732Y891713D03*
X839970Y981470D03*
X834470D03*
X826470D03*
X836953Y1023500D03*
X832800Y1147500D03*
X776800Y1169700D03*
X822500Y1331000D03*
Y1298000D03*
Y1294000D03*
X852000Y1402000D03*
Y1406000D03*
X822500Y1373500D03*
Y1369500D03*
X835000Y1402500D03*
Y1398000D03*
X822500Y1335000D03*
X772361Y1451972D03*
X909423Y354393D03*
X898059Y343029D03*
X902184Y347219D03*
X906616Y351586D03*
X945408Y378761D03*
X870400Y454315D03*
X944387Y520100D03*
X941557Y547005D03*
X935490Y519550D03*
X884801Y630225D03*
X892400Y633700D03*
X867260Y608600D03*
X883030Y611940D03*
X878600Y615600D03*
X879600Y621600D03*
X878400Y626200D03*
X924484Y812558D03*
X921047Y811463D03*
X869989Y818847D03*
X931800Y791500D03*
X870001Y822862D03*
X934800Y795300D03*
X916855Y810934D03*
X909144Y803346D03*
X903700Y803200D03*
X912762Y792801D03*
X903221Y793938D03*
X912030Y787650D03*
X907800Y788700D03*
X913059Y810367D03*
X906166Y812784D03*
X902560Y813313D03*
X876862Y842155D03*
X881702Y838859D03*
X874593Y763800D03*
X874821Y767690D03*
X931380Y821500D03*
X935485Y821400D03*
X903572Y773740D03*
X931206Y845756D03*
X920170Y857430D03*
X903500Y769900D03*
X939500Y842400D03*
X924670Y857430D03*
X866655Y855100D03*
X870200Y852203D03*
X943294Y838833D03*
X903300Y763200D03*
X894317Y865406D03*
X890117D03*
X894317Y861206D03*
X890117D03*
X879667Y877303D03*
X884684Y877406D03*
X947700Y1185500D03*
X947500Y1233000D03*
X955500D03*
X869937Y1400312D03*
X945415Y1429318D03*
X945414Y1412818D03*
X1038067Y441886D03*
X1021890Y439717D03*
X991538Y522018D03*
X1000051Y547644D03*
X991360Y529780D03*
X977676Y828513D03*
X1005272Y837091D03*
X1000827Y837072D03*
X973070Y828512D03*
X996938Y901170D03*
X1034200Y945000D03*
X1040200D03*
X1046272Y944928D03*
X1039500Y874700D03*
X1024129Y946152D03*
X1044800Y893750D03*
X1030862Y951946D03*
X1022080Y960728D03*
X1030178Y1134165D03*
X965500Y1128000D03*
X1029000Y1122400D03*
X977643Y1132490D03*
X982500Y1213000D03*
Y1221000D03*
Y1225000D03*
Y1205000D03*
X964550Y1190200D03*
X996693Y1421399D03*
X988693D03*
X1039900Y1417000D03*
X1049260Y1466691D03*
X962136Y1431831D03*
X1033253Y1444649D03*
X1048553Y1448399D03*
X1130800Y472900D03*
X1131800Y446800D03*
X1136000Y446849D03*
X1113593Y476094D03*
X1102677Y487116D03*
X1119242Y477261D03*
X1134600Y618747D03*
X1118505Y658863D03*
X1114905Y658882D03*
X1129500Y619200D03*
X1138900Y584900D03*
X1112682Y681223D03*
X1107674Y677776D03*
X1141230Y673825D03*
X1103770Y675413D03*
X1075706Y941261D03*
X1058800Y893750D03*
X1093588Y972000D03*
X1110600Y964200D03*
X1108500Y960600D03*
X1104600Y967800D03*
X1101950Y962900D03*
X1101600Y953700D03*
X1087962Y959252D03*
X1068569Y1191530D03*
X1072931Y1191482D03*
X1072900Y1204500D03*
X1084571Y1200129D03*
X1072600Y1211400D03*
X1084400Y1204200D03*
X1083100Y1305600D03*
X1078850Y1287900D03*
X1096280Y1288150D03*
X1092475Y1287971D03*
X1133480Y1296700D03*
Y1291700D03*
X1121346Y1307385D03*
Y1311385D03*
X1117000Y1332500D03*
Y1328500D03*
X1072120Y1292460D03*
X1091000Y1393500D03*
X1086646Y1396419D03*
X1160900Y468500D03*
X1156110Y473330D03*
X1152600Y468470D03*
X1201000Y447000D03*
X1200500Y452000D03*
X1167000Y586500D03*
X1169125Y581776D03*
X1166550Y579200D03*
X1177350Y597792D03*
X1155600Y1074500D03*
X1216894Y1304283D03*
Y1308283D03*
X1183894Y1304783D03*
Y1308783D03*
X1180614Y1340033D03*
X1213820D03*
X1208394Y1346763D03*
X1193894D03*
X1227100D03*
X1203312Y1402793D03*
X1241600Y1346763D03*
X1308000Y35000D03*
X1261100Y16600D03*
X1264700Y16400D03*
X1312000Y501500D03*
Y954000D03*
X1260000Y993500D03*
X1334500Y1007000D03*
X1289574Y1483700D03*
X1252674Y1496800D03*
X1266474Y1487500D03*
X1278574Y1488700D03*
X1282374Y1445500D03*
Y1464000D03*
X1296374Y1430700D03*
X1297089Y1450307D03*
X1322000Y1430700D03*
X1284624Y1476400D03*
X1260574Y1445600D03*
X1256474Y1446000D03*
X1436000Y48500D03*
Y501500D03*
X1383200Y992700D03*
X1436000Y954000D03*
X1506000Y993000D03*
X1557500Y35000D03*
X1560500Y501500D03*
Y954000D03*
X1684500Y48500D03*
Y501500D03*
X1631500Y994000D03*
X1684500Y954000D03*
X1676511Y1292495D03*
X1662626Y1445500D03*
X1674926Y1447400D03*
X1661626Y1480000D03*
X1811600Y32800D03*
X1794300Y63400D03*
X1803620Y57000D03*
X1807500Y57400D03*
X1755159Y469723D03*
X1808500Y501500D03*
Y954000D03*
X1756000Y993500D03*
X1800326Y1445800D03*
X1794426Y1446400D03*
X1891300Y49400D03*
X1880500Y48900D03*
X1842400Y29500D03*
X1836476Y467034D03*
X1853000Y504000D03*
X1875800Y981000D03*
X1853000Y957000D03*
X1827600Y970700D03*
X1919000Y51000D03*
X1918800Y1112100D03*
G54D21*
G01X1127703Y569663D02*
X1129021D01*
G02X1129884Y568800I0J-863D01*
G01Y568100D01*
G02X1128479Y566695I-1405J0D01*
G01X1087599D01*
X999649Y509574D01*
X911784Y452506D01*
X850010Y357372D01*
X849250Y357211D01*
X848351Y355827D01*
X848513Y355066D01*
X847614Y353682D01*
X846853Y353520D01*
X845955Y352137D01*
X846117Y351376D01*
X845218Y349992D01*
X844457Y349830D01*
X843559Y348446D01*
X843720Y347685D01*
X842822Y346302D01*
X842061Y346140D01*
X841162Y344756D01*
X841324Y343995D01*
X829740Y326155D01*
Y281136D01*
G02X829100Y280496I-640J0D01*
G01X827500D01*
G02X826772Y281224I0J728D01*
G01Y282677D01*
G01X1133215Y569663D02*
X1131897D01*
G03X1131034Y568800I0J-863D01*
G01Y568100D01*
G02X1128479Y565545I-2555J0D01*
G01X1087940D01*
X1044108Y537076D01*
X1000276Y508609D01*
X912616Y451674D01*
X833699Y330139D01*
X830890Y325814D01*
Y281136D01*
G02X829100Y279346I-1790J0D01*
G01X827500D01*
G03X826772Y278618I0J-728D01*
G01Y277165D01*
G01X1123766Y562576D02*
X1125084D01*
G02X1125947Y561713I0J-863D01*
G01Y561013D01*
G02X1124542Y559608I-1405J0D01*
G01X1089721D01*
X916548Y447154D01*
X879136Y389539D01*
X878376Y389377D01*
X877477Y387993D01*
X877639Y387232D01*
X876740Y385848D01*
X875979Y385686D01*
X875081Y384303D01*
X875243Y383542D01*
X874344Y382158D01*
X873583Y381996D01*
X872685Y380612D01*
X872846Y379852D01*
X871948Y378468D01*
X871187Y378306D01*
X870288Y376922D01*
X870450Y376161D01*
X836827Y324379D01*
Y263100D01*
G02X835325Y261598I-1502J0D01*
G01X834587D01*
G02X833859Y262326I0J728D01*
G01Y263779D01*
G01X1129278Y562576D02*
X1127960D01*
G03X1127097Y561713I0J-863D01*
G01Y561013D01*
G02X1124542Y558458I-2555J0D01*
G01X1090062D01*
X917380Y446322D01*
X837977Y324038D01*
Y263100D01*
G02X835325Y260448I-2652J0D01*
G01X834587D01*
G03X833859Y259720I0J-728D01*
G01Y258268D01*
G01X1127703Y555490D02*
X1129021D01*
G02X1129884Y554627I0J-863D01*
G01Y553927D01*
G02X1128479Y552522I-1405J0D01*
G01X1088551D01*
X924301Y445852D01*
X894053Y399260D01*
X893293Y399099D01*
X892394Y397715D01*
X892556Y396954D01*
X891657Y395570D01*
X890897Y395408D01*
X889998Y394024D01*
X890160Y393263D01*
X889262Y391879D01*
X888501Y391718D01*
X887602Y390334D01*
X887764Y389573D01*
X886866Y388189D01*
X886105Y388027D01*
X885206Y386643D01*
X885368Y385882D01*
X843913Y322028D01*
Y281998D01*
G02X842411Y280496I-1502J0D01*
G01X841673D01*
G02X840945Y281224I0J728D01*
G01Y282677D01*
G01X1133215Y555490D02*
X1131897D01*
G03X1131034Y554627I0J-863D01*
G01Y553927D01*
G02X1128479Y551372I-2555J0D01*
G01X1088892D01*
X925133Y445020D01*
X845063Y321687D01*
Y281998D01*
G02X842411Y279346I-2652J0D01*
G01X841673D01*
G03X840945Y278618I0J-728D01*
G01Y277165D01*
G01X1123766Y548403D02*
X1125084D01*
G02X1125947Y547540I0J-863D01*
G01Y546840D01*
G02X1124542Y545435I-1405J0D01*
G01X1091572D01*
X926105Y437981D01*
X911928Y416144D01*
X911168Y415982D01*
X910269Y414598D01*
X910431Y413838D01*
X909532Y412454D01*
X908772Y412292D01*
X907873Y410908D01*
X908035Y410147D01*
X907137Y408763D01*
X906376Y408601D01*
X905477Y407217D01*
X905639Y406457D01*
X904741Y405073D01*
X903980Y404911D01*
X903081Y403527D01*
X903243Y402766D01*
X851000Y322292D01*
Y263100D01*
G02X849498Y261598I-1502J0D01*
G01X848760D01*
G02X848032Y262326I0J728D01*
G01Y263779D01*
G01X1129278Y548403D02*
X1127960D01*
G03X1127097Y547540I0J-863D01*
G01Y546840D01*
G02X1124542Y544285I-2555J0D01*
G01X1091913D01*
X926937Y437149D01*
X852150Y321951D01*
Y263100D01*
G02X849498Y260448I-2652J0D01*
G01X848760D01*
G03X848032Y259720I0J-728D01*
G01Y258268D01*
G01X1127703Y541317D02*
X1129021D01*
G02X1129884Y540454I0J-863D01*
G01Y539754D01*
G02X1128479Y538349I-1405J0D01*
G01X1090646D01*
X930843Y434568D01*
X881869Y359149D01*
X881108Y358987D01*
X880209Y357603D01*
X880371Y356843D01*
X879472Y355459D01*
X878712Y355297D01*
X877813Y353913D01*
X877975Y353152D01*
X877076Y351769D01*
X876315Y351607D01*
X875417Y350223D01*
X875578Y349462D01*
X874680Y348078D01*
X873919Y347917D01*
X873020Y346533D01*
X873182Y345772D01*
X858086Y322524D01*
Y281998D01*
G02X856584Y280496I-1502J0D01*
G01X855846D01*
G02X855118Y281224I0J728D01*
G01Y282677D01*
G01X1133215Y541317D02*
X1131897D01*
G03X1131034Y540454I0J-863D01*
G01Y539754D01*
G02X1128479Y537199I-2555J0D01*
G01X1090987D01*
X931675Y433736D01*
X859236Y322183D01*
Y281998D01*
G02X856584Y279346I-2652J0D01*
G01X855846D01*
G03X855118Y278618I0J-728D01*
G01Y277165D01*
G01X1123766Y534230D02*
X1125084D01*
G02X1125947Y533367I0J-863D01*
G01Y532667D01*
G02X1124542Y531262I-1405J0D01*
G01X1092350D01*
X932975Y427763D01*
X883316Y351326D01*
X882555Y351164D01*
X881656Y349780D01*
X881818Y349020D01*
X880919Y347636D01*
X880158Y347474D01*
X879259Y346090D01*
X879421Y345330D01*
X878522Y343946D01*
X877761Y343784D01*
X876862Y342400D01*
X877024Y341640D01*
X876125Y340256D01*
X875364Y340094D01*
X874465Y338711D01*
X874627Y337950D01*
X868396Y328359D01*
X865173Y313184D01*
Y263100D01*
G02X863671Y261598I-1502J0D01*
G01X862933D01*
G02X862205Y262326I0J728D01*
G01Y263779D01*
G01X1129278Y534230D02*
X1127960D01*
G03X1127097Y533367I0J-863D01*
G01Y532667D01*
G02X1124542Y530112I-2555J0D01*
G01X1092691D01*
X933807Y426931D01*
X869477Y327911D01*
X866323Y313063D01*
Y263100D01*
G02X863671Y260448I-2652J0D01*
G01X862933D01*
G03X862205Y259720I0J-728D01*
G01Y258268D01*
G01X1127703Y527143D02*
X1129021D01*
G02X1129884Y526280I0J-863D01*
G01Y525580D01*
G02X1128479Y524175I-1405J0D01*
G01X1091016D01*
X936716Y423972D01*
X877002Y332059D01*
X876656Y330283D01*
X876058Y329879D01*
X875744Y328260D01*
X876147Y327661D01*
X875833Y326042D01*
X875141Y325575D01*
X874826Y323955D01*
X875293Y323264D01*
X874978Y321644D01*
X874286Y321177D01*
X873972Y319558D01*
X874438Y318866D01*
X874123Y317246D01*
X873536Y316850D01*
X873221Y315230D01*
X873617Y314644D01*
X873009Y311512D01*
X872260Y307657D01*
Y281998D01*
G02X870758Y280496I-1502J0D01*
G01X870020D01*
G02X869292Y281224I0J728D01*
G01Y282677D01*
G01X1133215Y527143D02*
X1131897D01*
G03X1131034Y526280I0J-863D01*
G01Y525580D01*
G02X1128479Y523025I-2555J0D01*
G01X1091357D01*
X937548Y423140D01*
X878089Y331620D01*
X873410Y307546D01*
Y281998D01*
G02X870758Y279346I-2652J0D01*
G01X870020D01*
G03X869292Y278618I0J-728D01*
G01Y277165D01*
G01X1123766Y520057D02*
X1125084D01*
G02X1125947Y519194I0J-863D01*
G01Y515514D01*
X1123610Y513181D01*
X931114Y388086D01*
X926456Y385060D01*
Y385065D01*
X925701Y385225D01*
X924318Y384326D01*
X924156Y383564D01*
X922773Y382665D01*
X921956Y382838D01*
X920573Y381939D01*
X920400Y381123D01*
X919016Y380224D01*
X918200Y380397D01*
X916816Y379498D01*
X916643Y378682D01*
X915260Y377783D01*
X914443Y377956D01*
X913060Y377057D01*
X912887Y376241D01*
X909157Y373817D01*
X901751Y362410D01*
X898287Y357074D01*
X887434Y340357D01*
X879346Y302081D01*
Y263100D01*
G02X877844Y261598I-1502J0D01*
G01X877106D01*
G02X876378Y262326I0J728D01*
G01Y263779D01*
G01X1129278Y520057D02*
X1127960D01*
G03X1127097Y519194I0J-863D01*
G01Y515037D01*
X1124338Y512281D01*
X909989Y372985D01*
X888515Y339910D01*
X880496Y301960D01*
Y263100D01*
G02X877844Y260448I-2652J0D01*
G01X877106D01*
G03X876378Y259720I0J-728D01*
G01Y258268D01*
G54D12*
G01X95800Y71800D02*
X101405D01*
X151676Y21529D01*
X185551D01*
G01X30500Y67000D02*
X74000D01*
X78800Y71800D01*
X95800D01*
G01X213214Y397600D02*
X211034Y395420D01*
X180280D01*
X177754Y397946D01*
X84581D01*
G01X79581D02*
X84581D01*
G01X95500Y525500D02*
X98500D01*
X122000Y502000D01*
X186800D01*
X210100Y525300D01*
X218700D01*
X220000Y524000D01*
G01X95500Y972500D02*
X105500D01*
X125500Y992500D01*
G01X705171Y16254D02*
X705115Y16310D01*
X201368D01*
X189078Y28600D01*
X175650D01*
G01X145864Y33216D02*
X150480Y28600D01*
X175650D01*
G01X125500Y992500D02*
X179617D01*
X188917Y983200D01*
X211300D01*
X216400Y978100D01*
X220000D01*
G01X215500Y80500D02*
X216000D01*
X250250Y46250D01*
X317600D01*
X340650Y69300D01*
G01X315514Y397600D02*
X313207Y395293D01*
X295559D01*
X293252Y397600D01*
X218214D01*
G01X213214D02*
X218214D01*
G01X220000Y524000D02*
X223000D01*
X249500Y497500D01*
X302300D01*
X330000Y525200D01*
X344100D01*
G01X220000Y978100D02*
Y978200D01*
G01X344200D02*
X329300D01*
X318400Y989100D01*
X302900D01*
X299500Y992500D01*
X252000D01*
G01D02*
X247000D01*
X232600Y978100D01*
X220000D01*
G01X340650Y69300D02*
X350563D01*
X373363Y46500D01*
X419500D01*
X453500Y80500D01*
X464000D01*
G01X315514Y397600D02*
X320514D01*
G01X344100Y525200D02*
X344000Y525300D01*
G01X464801Y521156D02*
X453056D01*
X430900Y499000D01*
X373700D01*
X347500Y525200D01*
X344100D01*
G01X468300Y978000D02*
X452800D01*
X444300Y986500D01*
X426000D01*
X419500Y993000D01*
X376000D01*
G01D02*
X361200Y978200D01*
X344200D01*
G01X466941Y-145664D02*
Y-225664D01*
G01D02*
X1593241D01*
G01X462941Y-129664D02*
G02I-12000J0D01*
G01X457791D02*
G02I-6850J0D01*
G01X450941Y-145664D02*
Y-113664D01*
G01X466941Y-129664D02*
X434941D01*
G01X466941Y-145664D02*
X1593241D01*
G01X466941Y-181164D02*
X1593241D01*
G01X464000Y80500D02*
X496250Y48250D01*
X563750D01*
X585000Y69500D01*
X589150D01*
G01X592500Y525300D02*
X587028D01*
X562228Y500500D01*
X495500D01*
X474844Y521156D01*
X464801D01*
G01X500000Y992000D02*
X495372D01*
X481372Y978000D01*
X468300D01*
G01X592800Y978100D02*
X580900D01*
X570500Y988500D01*
X509590D01*
X506090Y992000D01*
X500000D01*
G01X589150Y69500D02*
X599000D01*
X636182Y32318D01*
X680445D01*
X707342Y59215D01*
Y75260D01*
X709000Y76918D01*
Y79500D01*
G01X716400Y525200D02*
X706846D01*
X683144Y501498D01*
X619091D01*
X595289Y525300D01*
X592500D01*
G01X716800Y978300D02*
X707600D01*
X696700Y989200D01*
X677174D01*
X673374Y993000D01*
X624500D01*
G01D02*
X609600Y978100D01*
X592800D01*
G01X637972Y1441419D02*
X637971Y1441418D01*
Y1425400D01*
G01X613400Y1408100D02*
Y1419842D01*
X618477Y1424919D01*
X637490D01*
X637971Y1425400D01*
G01X826470Y981470D02*
X815440Y992500D01*
X755300D01*
X755200Y992400D01*
G01D02*
X755100Y992500D01*
X745000D01*
X730800Y978300D01*
X716800D01*
G01X1034200Y945000D02*
Y966300D01*
X953392Y1047108D01*
X797608D01*
X759300Y1008800D01*
X759249D01*
G01X718900Y1472800D02*
Y1485470D01*
X712270Y1492100D01*
X688400D01*
X679800Y1483500D01*
G01X805741Y-145664D02*
Y-225664D01*
G01X870400Y454315D02*
X866360Y450275D01*
X845602D01*
X841562Y454315D01*
X808395D01*
G01X815400Y892800D02*
X836700D01*
X847100Y903200D01*
X869133D01*
X875000Y897333D01*
X944732D01*
X945940Y897076D01*
X952516Y890500D01*
X965137D01*
X970500Y895863D01*
X981788D01*
X981869Y895782D01*
X991550D01*
X996938Y901170D01*
G01X834470Y981470D02*
X831000Y978000D01*
X828500D01*
X826470Y980030D01*
Y981470D01*
G01X839970D02*
X834470D01*
G01X943241Y-145664D02*
Y-225664D01*
G01X1040200Y945000D02*
X1044997Y949797D01*
X1102797D01*
X1123067Y970067D01*
Y975299D01*
X1166268Y1018500D01*
X1260000D01*
X1272420Y1006080D01*
X1333580D01*
X1334500Y1007000D01*
G01X1046272Y944928D02*
X1105428D01*
X1127679Y967179D01*
Y974594D01*
X1168585Y1015500D01*
X1258757D01*
X1271177Y1003080D01*
X1313220D01*
X1327125Y989175D01*
X1356175D01*
X1380309Y1013309D01*
X1778991D01*
X1821600Y970700D01*
X1827600D01*
G01X1058241Y-145664D02*
Y-225664D01*
G01X1225741Y-145664D02*
Y-225664D01*
G01X1436000Y48500D02*
X1432141Y44641D01*
X1392641D01*
X1383000Y35000D01*
X1308000D01*
G01X1312000Y501500D02*
X1315000Y498500D01*
X1433000D01*
X1436000Y501500D01*
G01X1312000Y954000D02*
X1293500Y972500D01*
Y982000D01*
X1282000Y993500D01*
X1260000D01*
G01X1383200Y992700D02*
X1369500D01*
X1340232Y963432D01*
X1321432D01*
X1312000Y954000D01*
G01X1395741Y-145664D02*
Y-225664D01*
G01X1436000Y954000D02*
X1422000Y968000D01*
Y978500D01*
X1407800Y992700D01*
X1383200D01*
G01X1557500Y35000D02*
X1553000Y30500D01*
X1462500D01*
X1444500Y48500D01*
X1436000D01*
G01Y501500D02*
X1439500D01*
X1444000Y497000D01*
X1556000D01*
X1560500Y501500D01*
G01X1506000Y993000D02*
X1486500D01*
X1456500Y963000D01*
X1448006D01*
X1439006Y954000D01*
X1436000D01*
G01X1560500D02*
X1547000Y967500D01*
Y975500D01*
X1529500Y993000D01*
X1506000D01*
G01X1593241Y-145664D02*
Y-225664D01*
G01X1621241Y-129664D02*
G02I-12000J0D01*
G01X1616091D02*
G02I-6850J0D01*
G01X1609241Y-145664D02*
Y-113664D01*
G01X1625241Y-129664D02*
X1593241D01*
G01X1684500Y48500D02*
X1680000Y44000D01*
X1647500D01*
X1638500Y35000D01*
X1557500D01*
G01X1560500Y501500D02*
X1565500D01*
X1570000Y497000D01*
X1680000D01*
X1684500Y501500D01*
G01X1631500Y994000D02*
X1610500D01*
X1577500Y961000D01*
X1573000D01*
X1566000Y954000D01*
X1560500D01*
G01X1794300Y63400D02*
X1787700Y56800D01*
Y42100D01*
X1779400Y33800D01*
X1711200D01*
X1696500Y48500D01*
X1684500D01*
G01Y501500D02*
X1690500D01*
X1694000Y498000D01*
X1805000D01*
X1808500Y501500D01*
G01X1684500Y954000D02*
X1668750Y969750D01*
Y979750D01*
X1654500Y994000D01*
X1631500D01*
G01X1756000Y993500D02*
X1734000D01*
X1703000Y962500D01*
X1694000D01*
X1685500Y954000D01*
X1684500D01*
G01X1674926Y1447400D02*
X1673926Y1446400D01*
X1663526D01*
X1662626Y1445500D01*
G01X1811600Y32800D02*
Y48600D01*
X1815100Y52100D01*
Y59969D01*
X1811669Y63400D01*
X1794300D01*
G01X1842400Y29500D02*
X1841100Y28200D01*
X1816200D01*
X1811600Y32800D01*
G01X1808500Y501500D02*
X1811500Y498500D01*
X1847500D01*
X1853000Y504000D01*
G01X1808500Y954000D02*
X1798000Y964500D01*
Y972000D01*
X1776500Y993500D01*
X1756000D01*
G01X1853000Y957000D02*
X1850000Y954000D01*
X1808500D01*
G01X1919000Y51000D02*
X1913000Y45000D01*
X1895700D01*
X1891300Y49400D01*
G01X1880500Y48900D02*
X1866600Y35000D01*
X1847900D01*
X1842400Y29500D01*
G01X1891300Y49400D02*
X1888200Y46300D01*
X1883100D01*
X1880500Y48900D01*
G01X1875800Y981000D02*
X1870200D01*
X1855800Y966600D01*
Y959800D01*
X1853000Y957000D01*
X127988Y71319D03*
Y76319D03*
Y524075D03*
Y529075D03*
Y976831D03*
Y981831D03*
X252200Y71319D03*
Y76319D03*
Y524075D03*
Y529075D03*
Y976831D03*
Y981831D03*
X376413Y71319D03*
Y76319D03*
Y524075D03*
Y529075D03*
Y976831D03*
Y981831D03*
X500625Y71319D03*
Y76319D03*
Y524075D03*
Y529075D03*
Y976831D03*
Y981831D03*
X624838Y71319D03*
Y76319D03*
Y524075D03*
Y529075D03*
Y976831D03*
Y981831D03*
X749051Y71319D03*
Y76319D03*
Y524075D03*
Y529075D03*
Y976831D03*
Y981831D03*
X1275400Y68650D03*
X1270400D03*
X1275400Y521406D03*
X1270400D03*
X1273975Y976831D03*
Y981831D03*
X1399613Y68650D03*
X1394613D03*
X1399613Y521406D03*
X1394613D03*
X1398188Y976831D03*
Y981831D03*
X1523825Y68650D03*
X1518825D03*
X1523825Y521406D03*
X1518825D03*
X1522400Y976831D03*
Y981831D03*
X1648038Y68650D03*
X1643038D03*
X1648038Y521406D03*
X1643038D03*
X1646613Y976831D03*
Y981831D03*
X1772250Y68650D03*
X1767250D03*
X1772250Y521406D03*
X1767250D03*
X1770825Y976831D03*
Y981831D03*
X1896463Y68650D03*
X1891463D03*
X1896463Y521406D03*
X1891463D03*
X1895038Y976831D03*
Y981831D03*
G54D22*
G01X1133215Y769663D02*
X1131763D01*
G03X1131121Y769021I0J-642D01*
G01Y768121D01*
G02X1128457Y765457I-2664J0D01*
G01X1088230D01*
X1081874Y764106D01*
X1060848Y750446D01*
X996319Y651056D01*
X529804Y348105D01*
X390995Y318600D01*
X330565Y279354D01*
X240657Y140886D01*
X205843Y118165D01*
X136880Y73156D01*
X128463D01*
G03X127988Y72681I0J-475D01*
G01Y71319D01*
G01X1127703Y769663D02*
X1129154D01*
G02X1129796Y769021I0J-642D01*
G01Y768121D01*
G02X1128457Y766782I-1339J0D01*
G01X1088090D01*
X1081358Y765351D01*
X1059890Y751404D01*
X995361Y652014D01*
X529288Y349350D01*
X390479Y319845D01*
X329607Y280312D01*
X239698Y141843D01*
X170538Y96706D01*
X169376Y96950D01*
X168183Y96171D01*
X167938Y95009D01*
X166745Y94230D01*
X165582Y94474D01*
X164389Y93695D01*
X164145Y92533D01*
X162951Y91754D01*
X161789Y91998D01*
X160595Y91219D01*
X160351Y90057D01*
X136485Y74481D01*
X128463D01*
G02X127988Y74956I0J475D01*
G01Y76319D01*
G01X1133215Y854703D02*
X1131763D01*
G03X1131121Y854061I0J-642D01*
G01Y853161D01*
G02X1128457Y850497I-2664J0D01*
G01X1064073D01*
X1042027Y845811D01*
X796762Y686521D01*
X200466Y559774D01*
X157998Y536862D01*
X157997Y536861D01*
X147291Y531085D01*
Y531086D01*
X137701Y525912D01*
X128463D01*
G03X127988Y525437I0J-475D01*
G01Y524075D01*
G01X1127703Y854703D02*
X1129154D01*
G02X1129796Y854061I0J-642D01*
G01Y853161D01*
G02X1128457Y851822I-1339J0D01*
G01X1063933D01*
X1041511Y847056D01*
X796246Y687766D01*
X200004Y561031D01*
X157368Y538028D01*
X156230Y538368D01*
X154975Y537692D01*
X154635Y536554D01*
X153381Y535877D01*
X152243Y536217D01*
X150989Y535541D01*
X150648Y534403D01*
X149394Y533726D01*
X148256Y534067D01*
X147002Y533390D01*
X146661Y532252D01*
X137366Y527237D01*
X128463D01*
G02X127988Y527712I0J475D01*
G01Y529075D01*
G01X1129278Y904309D02*
X1127826D01*
G03X1127184Y903667I0J-642D01*
G01Y902767D01*
G02X1124520Y900103I-2664J0D01*
G01X1030400D01*
X996028Y908435D01*
X952053Y899088D01*
X876451Y915157D01*
X679607Y873513D01*
X416879Y923944D01*
Y923945D01*
X131742Y978668D01*
X128463D01*
G03X127988Y978193I0J-475D01*
G01Y976831D01*
G01X1123766Y904309D02*
X1125217D01*
G02X1125859Y903667I0J-642D01*
G01Y902767D01*
G02X1124520Y901428I-1339J0D01*
G01X1030559D01*
X996047Y909794D01*
X952053Y900443D01*
X876452Y916512D01*
X679594Y874865D01*
X428536Y923057D01*
X427869Y924040D01*
X426470Y924309D01*
X425486Y923642D01*
X424087Y923911D01*
X423420Y924894D01*
X422021Y925163D01*
X421038Y924496D01*
X419638Y924765D01*
X418972Y925748D01*
X417572Y926017D01*
X416589Y925350D01*
X131868Y979993D01*
X128463D01*
G02X127988Y980468I0J475D01*
G01Y981831D01*
G01X1129278Y762577D02*
X1127826D01*
G03X1127184Y761935I0J-642D01*
G01Y761035D01*
G02X1124520Y758371I-2664J0D01*
G01X1088029D01*
X1084943Y757715D01*
X1060335Y741736D01*
X997184Y644490D01*
X474211Y304878D01*
X360335Y136049D01*
X270275Y75300D01*
X270274Y75298D01*
X267097Y73156D01*
X252675D01*
G03X252200Y72681I0J-475D01*
G01Y71319D01*
G01X1123766Y762577D02*
X1125217D01*
G02X1125859Y761935I0J-642D01*
G01Y761035D01*
G02X1124520Y759696I-1339J0D01*
G01X1087889D01*
X1084427Y758960D01*
X1059377Y742694D01*
X996226Y645448D01*
X473263Y305843D01*
X359380Y137004D01*
X279162Y82893D01*
X277996Y83120D01*
X276814Y82323D01*
X276588Y81157D01*
X275406Y80360D01*
X274240Y80587D01*
X273059Y79790D01*
X272832Y78624D01*
X271651Y77827D01*
X270485Y78053D01*
X269303Y77257D01*
X269077Y76090D01*
X266691Y74481D01*
X252675D01*
G02X252200Y74956I0J475D01*
G01Y76319D01*
G01X1129278Y847616D02*
X1127826D01*
G03X1127184Y846974I0J-642D01*
G01Y846074D01*
G02X1124520Y843410I-2664J0D01*
G01X1077635D01*
X1042300Y835892D01*
X775611Y662713D01*
X355036Y573321D01*
X313292Y546217D01*
X257430Y525912D01*
X252675D01*
G03X252200Y525437I0J-475D01*
G01Y524075D01*
G01X1123766Y847616D02*
X1125217D01*
G02X1125859Y846974I0J-642D01*
G01Y846074D01*
G02X1124520Y844735I-1339J0D01*
G01X1077495D01*
X1041784Y837137D01*
X775095Y663958D01*
X354520Y574566D01*
X312697Y547411D01*
X282294Y536360D01*
X281269Y536839D01*
X279930Y536352D01*
X279451Y535327D01*
X278112Y534840D01*
X277087Y535318D01*
X275748Y534832D01*
X275269Y533807D01*
X273930Y533320D01*
X272905Y533798D01*
X271565Y533312D01*
X271087Y532286D01*
X257195Y527237D01*
X252675D01*
G02X252200Y527712I0J475D01*
G01Y529075D01*
G01X1133215Y911396D02*
X1131763D01*
G03X1131121Y910754I0J-642D01*
G01Y909854D01*
G02X1128457Y907190I-2664J0D01*
G01X1024104D01*
X992427Y913923D01*
X948349Y904552D01*
X875605Y920016D01*
X729431Y890242D01*
X255147Y978668D01*
X252675D01*
G03X252200Y978193I0J-475D01*
G01Y976831D01*
G01X1127703Y911396D02*
X1129154D01*
G02X1129796Y910754I0J-642D01*
G01Y909854D01*
G02X1128457Y908515I-1339J0D01*
G01X1024244D01*
X992427Y915278D01*
X948349Y905907D01*
X875611Y921370D01*
X729420Y891592D01*
X487861Y936631D01*
X487221Y937564D01*
X485820Y937826D01*
X484887Y937186D01*
X483486Y937447D01*
X482847Y938380D01*
X481446Y938641D01*
X480513Y938001D01*
X479112Y938263D01*
X478472Y939196D01*
X477071Y939457D01*
X476138Y938817D01*
X384833Y955840D01*
X255286Y979993D01*
X252675D01*
G02X252200Y980468I0J475D01*
G01Y981831D01*
G01X1133215Y755490D02*
X1131763D01*
G03X1131121Y754848I0J-642D01*
G01Y753948D01*
G02X1128457Y751284I-2664J0D01*
G01X1085276D01*
X1063873Y737382D01*
X1000406Y639651D01*
X550228Y347327D01*
X395909Y109650D01*
X395451Y108946D01*
X393169Y105431D01*
X387182Y77269D01*
X385203Y74218D01*
X382401Y73156D01*
X376888D01*
G03X376413Y72681I0J-475D01*
G01Y71319D01*
G01X1127703Y755490D02*
X1129154D01*
G02X1129796Y754848I0J-642D01*
G01Y753948D01*
G02X1128457Y752609I-1339J0D01*
G01X1084883D01*
X1062915Y738340D01*
X1031027Y689237D01*
X999448Y640609D01*
X549270Y348285D01*
X402204Y121780D01*
X401098Y121545D01*
X400322Y120350D01*
X400557Y119243D01*
X399781Y118048D01*
X398674Y117813D01*
X397898Y116617D01*
X398134Y115511D01*
X397358Y114316D01*
X396251Y114081D01*
X395475Y112885D01*
X395711Y111779D01*
X395710D01*
X394567Y110019D01*
X394339Y109669D01*
X391924Y105947D01*
X385936Y77785D01*
X384327Y75304D01*
X382158Y74481D01*
X376888D01*
G02X376413Y74956I0J475D01*
G01Y76319D01*
G01X1133215Y840529D02*
X1131763D01*
G03X1131121Y839887I0J-642D01*
G01Y838987D01*
G02X1128457Y836323I-2664J0D01*
G01X1076401D01*
X1048934Y830484D01*
X748662Y635492D01*
X642058Y612832D01*
Y612833D01*
X524084Y587757D01*
Y587756D01*
X506299Y583977D01*
X488514Y580197D01*
X437565Y547105D01*
X381081Y525912D01*
X376888D01*
G03X376413Y525437I0J-475D01*
G01Y524075D01*
G01X1127703Y840529D02*
X1129154D01*
G02X1129796Y839887I0J-642D01*
G01Y838987D01*
G02X1128457Y837648I-1339J0D01*
G01X1076261D01*
X1048418Y831729D01*
X748146Y636737D01*
X535629Y591566D01*
X534680Y592182D01*
X533286Y591886D01*
X532670Y590937D01*
X531276Y590641D01*
X530280Y591288D01*
X528886Y590992D01*
X528239Y589996D01*
X526845Y589699D01*
X525849Y590346D01*
X524455Y590050D01*
X523808Y589054D01*
X487998Y581442D01*
X436964Y548295D01*
X380840Y527237D01*
X376888D01*
G02X376413Y527712I0J475D01*
G01Y529075D01*
G01X1129278Y918482D02*
X1127826D01*
G03X1127184Y917840I0J-642D01*
G01Y916940D01*
G02X1124520Y914276I-2664J0D01*
G01X1017758D01*
X991233Y919913D01*
X948784Y910889D01*
X874366Y926709D01*
X749664Y899951D01*
X380210Y978668D01*
X376888D01*
G03X376413Y978193I0J-475D01*
G01Y976831D01*
G01X1123766Y918482D02*
X1125217D01*
G02X1125859Y917840I0J-642D01*
G01Y916940D01*
G02X1124520Y915601I-1339J0D01*
G01X1017898D01*
X991233Y921268D01*
X948784Y912244D01*
X874365Y928064D01*
X749663Y901306D01*
X567108Y940202D01*
X566462Y941199D01*
X565068Y941496D01*
X564071Y940849D01*
X562678Y941146D01*
X562031Y942143D01*
X560637Y942440D01*
X559641Y941793D01*
X558247Y942090D01*
X557601Y943087D01*
X556207Y943384D01*
X555210Y942737D01*
X380350Y979993D01*
X376888D01*
G02X376413Y980468I0J475D01*
G01Y981831D01*
G01X1129278Y748403D02*
X1127826D01*
G03X1127184Y747761I0J-642D01*
G01Y746861D01*
G02X1124520Y744197I-2664J0D01*
G01X1087628D01*
X1066505Y730479D01*
X1003396Y633302D01*
X653759Y406245D01*
X557801Y258483D01*
X522554Y92647D01*
X522108Y90552D01*
X521663Y88457D01*
X521166Y86121D01*
X513492Y74300D01*
X509643Y73156D01*
X501100D01*
G03X500625Y72681I0J-475D01*
G01Y71319D01*
G01X1123766Y748403D02*
X1125217D01*
G02X1125859Y747761I0J-642D01*
G01Y746861D01*
G02X1124520Y745522I-1339J0D01*
G01X1087235D01*
X1065547Y731437D01*
X1002438Y634260D01*
X652801Y407203D01*
X556556Y258999D01*
X524231Y106916D01*
X523235Y106269D01*
X522938Y104875D01*
X523585Y103878D01*
X523289Y102485D01*
X522293Y101837D01*
X521997Y100444D01*
X522644Y99447D01*
X522347Y98053D01*
X521351Y97406D01*
X521055Y96013D01*
X521702Y95016D01*
X520812Y90828D01*
X519921Y86637D01*
X512646Y75431D01*
X509450Y74481D01*
X501100D01*
G02X500625Y74956I0J475D01*
G01Y76319D01*
G01X1129278Y833443D02*
X1127826D01*
G03X1127184Y832801I0J-642D01*
G01Y831901D01*
G02X1124520Y829237I-2664J0D01*
G01X1091317D01*
X1048099Y820049D01*
X720202Y607214D01*
X612740Y584371D01*
X508180Y525912D01*
X501100D01*
G03X500625Y525437I0J-475D01*
G01Y524075D01*
G01X1123766Y833443D02*
X1125217D01*
G02X1125859Y832801I0J-642D01*
G01Y831901D01*
G02X1124520Y830562I-1339J0D01*
G01X1091177D01*
X1047583Y821294D01*
X719686Y608459D01*
X669183Y597724D01*
X654963Y594702D01*
X653967Y595349D01*
X652573Y595053D01*
X651926Y594056D01*
X650532Y593760D01*
X649536Y594407D01*
X648142Y594111D01*
X647495Y593115D01*
X646101Y592818D01*
X645105Y593465D01*
X643711Y593169D01*
X643064Y592173D01*
X643063Y592172D01*
X612268Y585626D01*
X507834Y527237D01*
X501100D01*
G02X500625Y527712I0J475D01*
G01Y529075D01*
G01X1133215Y925569D02*
X1131763D01*
G03X1131121Y924927I0J-642D01*
G01Y924027D01*
G02X1128457Y921363I-2664J0D01*
G01X1009895D01*
X992335Y925096D01*
X962914Y918841D01*
X878963Y936685D01*
X792716Y918167D01*
X652745Y947549D01*
Y947548D01*
X504500Y978668D01*
X501100D01*
G03X500625Y978193I0J-475D01*
G01Y976831D01*
G01X1127703Y925569D02*
X1129154D01*
G02X1129796Y924927I0J-642D01*
G01Y924027D01*
G02X1128457Y922688I-1339J0D01*
G01X1010035D01*
X992335Y926451D01*
X962914Y920196D01*
X878962Y938040D01*
X792713Y919522D01*
X653554Y948734D01*
X652904Y949728D01*
X651510Y950021D01*
X650515Y949372D01*
X649120Y949664D01*
X648471Y950659D01*
X647076Y950952D01*
X646082Y950302D01*
X644687Y950595D01*
X644038Y951590D01*
X642643Y951882D01*
X641648Y951233D01*
X504638Y979993D01*
X501100D01*
G02X500625Y980468I0J475D01*
G01Y981831D01*
G01X1133215Y741317D02*
X1131763D01*
G03X1131121Y740675I0J-642D01*
G01Y739775D01*
G02X1128457Y737111I-2664J0D01*
G01X1090335D01*
X1068248Y722769D01*
X1006660Y627931D01*
X752966Y463179D01*
X718155Y409575D01*
X700036Y324331D01*
X690761Y280693D01*
X662471Y147595D01*
X642316Y83561D01*
X630643Y73156D01*
X625313D01*
G03X624838Y72681I0J-475D01*
G01Y71319D01*
G01X1127703Y741317D02*
X1129154D01*
G02X1129796Y740675I0J-642D01*
G01Y739775D01*
G02X1128457Y738436I-1339J0D01*
G01X1089942D01*
X1067290Y723727D01*
X1005702Y628889D01*
X752008Y464137D01*
X716910Y410091D01*
X701269Y336505D01*
X700272Y335858D01*
X699976Y334464D01*
X700623Y333467D01*
X700327Y332073D01*
X699331Y331426D01*
X699034Y330033D01*
X699681Y329036D01*
X699385Y327642D01*
X698389Y326995D01*
X698092Y325602D01*
X698739Y324605D01*
X661187Y147933D01*
X641161Y84308D01*
X630138Y74481D01*
X625313D01*
G02X624838Y74956I0J475D01*
G01Y76319D01*
G01X1133215Y826356D02*
X1131763D01*
G03X1131121Y825714I0J-642D01*
G01Y824814D01*
G02X1128457Y822150I-2664J0D01*
G01X1090165D01*
X1029817Y801148D01*
X714255Y596271D01*
X683316Y548656D01*
X666377Y537655D01*
X638266Y525912D01*
X625313D01*
G03X624838Y525437I0J-475D01*
G01Y524075D01*
G01X1127703Y826356D02*
X1129154D01*
G02X1129796Y825714I0J-642D01*
G01Y824814D01*
G02X1128457Y823475I-1339J0D01*
G01X1089941D01*
X1065329Y814910D01*
X1064259Y815427D01*
X1062914Y814959D01*
X1062396Y813889D01*
X1061050Y813421D01*
X1059981Y813938D01*
X1058635Y813470D01*
X1058118Y812401D01*
X1056772Y811932D01*
X1055703Y812449D01*
X1054357Y811981D01*
X1053840Y810912D01*
X1029230Y802347D01*
X713297Y597229D01*
X682358Y549614D01*
X665755Y538832D01*
X638000Y527237D01*
X625313D01*
G02X624838Y527712I0J475D01*
G01Y529075D01*
G01X1129278Y932655D02*
X1127826D01*
G03X1127184Y932013I0J-642D01*
G01Y931113D01*
G02X1124520Y928449I-2664J0D01*
G01X1004244D01*
X991610Y931135D01*
X961503Y924737D01*
X842630Y950004D01*
X807424Y942902D01*
X726907Y960016D01*
X630570Y978668D01*
X625313D01*
G03X624838Y978193I0J-475D01*
G01Y976831D01*
G01X1123766Y932655D02*
X1125217D01*
G02X1125859Y932013I0J-642D01*
G01Y931113D01*
G02X1124520Y929774I-1339J0D01*
G01X1004384D01*
X991610Y932490D01*
X961503Y926092D01*
X842637Y951358D01*
X807431Y944256D01*
X726750Y961405D01*
X644828Y977258D01*
X644195Y978196D01*
X642796Y978467D01*
X641859Y977833D01*
X640459Y978104D01*
X639826Y979041D01*
X638427Y979312D01*
X637490Y978679D01*
X636091Y978949D01*
X635457Y979887D01*
X634058Y980158D01*
X633121Y979524D01*
X630697Y979993D01*
X625313D01*
G02X624838Y980468I0J475D01*
G01Y981831D01*
G01X1129278Y734230D02*
X1127826D01*
G03X1127184Y733588I0J-642D01*
G01Y732688D01*
G02X1124520Y730024I-2664J0D01*
G01X1094294D01*
X1073853Y716751D01*
X1012847Y622814D01*
X835166Y507423D01*
X814215Y475160D01*
X803738Y459027D01*
X798786Y451402D01*
X741077Y179845D01*
X750014Y137809D01*
X760933Y86457D01*
X758400Y76088D01*
X757960Y75802D01*
X753890Y73156D01*
X749526D01*
G03X749051Y72681I0J-475D01*
G01Y71319D01*
G01X1123766Y734230D02*
X1125217D01*
G02X1125859Y733588I0J-642D01*
G01Y732688D01*
G02X1124520Y731349I-1339J0D01*
G01X1093901D01*
X1072895Y717709D01*
X1011889Y623772D01*
X834208Y508381D01*
X823579Y492013D01*
X813103Y475882D01*
X802626Y459749D01*
X797541Y451918D01*
X749610Y226375D01*
X748661Y225759D01*
X748365Y224365D01*
X748981Y223416D01*
X748685Y222022D01*
X747736Y221406D01*
X747440Y220012D01*
X748056Y219063D01*
X747760Y217669D01*
X746811Y217052D01*
X746515Y215658D01*
X747131Y214710D01*
X739722Y179845D01*
X748718Y137533D01*
X759573Y86477D01*
X758405Y81696D01*
X757236Y76913D01*
X757237D01*
X753497Y74481D01*
X749526D01*
G02X749051Y74956I0J475D01*
G01Y76319D01*
G01X1129278Y819270D02*
X1127826D01*
G03X1127184Y818628I0J-642D01*
G01Y817728D01*
G02X1124520Y815064I-2664J0D01*
G01X1094827D01*
X1093235Y814269D01*
X988631Y653195D01*
X817314Y541937D01*
X756316Y525912D01*
X749526D01*
G03X749051Y525437I0J-475D01*
G01Y524075D01*
G01X1123766Y819270D02*
X1125217D01*
G02X1125859Y818628I0J-642D01*
G01Y817728D01*
G02X1124520Y816389I-1339J0D01*
G01X1094514D01*
X1092320Y815294D01*
X987673Y654153D01*
X816771Y543165D01*
X793977Y537177D01*
X792951Y537776D01*
X791573Y537413D01*
X790974Y536388D01*
X789595Y536026D01*
X788569Y536625D01*
X787191Y536262D01*
X786592Y535237D01*
X785214Y534874D01*
X784188Y535473D01*
X782810Y535111D01*
X782211Y534086D01*
X756143Y527237D01*
X749526D01*
G02X749051Y527712I0J475D01*
G01Y529075D01*
G01X1133215Y939742D02*
X1131763D01*
G03X1131121Y939100I0J-642D01*
G01Y938200D01*
G02X1128457Y935536I-2664J0D01*
G01X989404D01*
X975315Y932541D01*
X960799Y929456D01*
X752028Y978668D01*
X749526D01*
G03X749051Y978193I0J-475D01*
G01Y976831D01*
G01X1127703Y939742D02*
X1129154D01*
G02X1129796Y939100I0J-642D01*
G01Y938200D01*
G02X1128457Y936861I-1339J0D01*
G01X989264D01*
X960814Y930814D01*
X772597Y975181D01*
X772002Y976143D01*
X770615Y976470D01*
X769653Y975875D01*
X768266Y976202D01*
X767671Y977164D01*
X766284Y977491D01*
X765322Y976896D01*
X763935Y977223D01*
X763340Y978185D01*
X761953Y978512D01*
X760990Y977917D01*
X752183Y979993D01*
X749526D01*
G02X749051Y980468I0J475D01*
G01Y981831D01*
G01X1129278Y691711D02*
X1127928D01*
G03X1127184Y690967I0J-744D01*
G01Y689767D01*
G03X1127340Y689392I531J1D01*
G01X1127516Y689215D01*
X1127901Y688830D01*
X1148163Y681427D01*
X1162162Y672338D01*
X1185092Y637031D01*
X1265255Y200837D01*
X1266186Y200195D01*
X1266444Y198793D01*
X1265802Y197862D01*
X1266059Y196460D01*
X1266991Y195818D01*
X1267248Y194416D01*
X1266606Y193485D01*
X1266864Y192084D01*
X1267795Y191441D01*
X1268052Y190040D01*
X1267410Y189108D01*
X1273562Y155633D01*
Y69238D01*
G03X1274150Y68650I588J0D01*
G01X1275400D01*
G01X1123766Y691711D02*
X1125115D01*
G02X1125859Y690967I0J-744D01*
G01Y689766D01*
G03X1126402Y688456I1856J2D01*
G01X1126528Y688329D01*
X1127171Y687686D01*
X1147567Y680234D01*
X1161204Y671380D01*
X1183836Y636531D01*
X1272237Y155512D01*
Y69237D01*
G02X1271650Y68650I-587J0D01*
G01X1270400D01*
G01X1133215Y698797D02*
X1131865D01*
G03X1131121Y698053I0J-744D01*
G01Y696853D01*
G03X1132058Y695916I937J0D01*
G01X1135652D01*
X1170834Y673066D01*
X1196054Y634237D01*
X1226797Y489579D01*
X1308608Y363606D01*
X1309715Y363370D01*
X1310491Y362175D01*
X1310256Y361069D01*
X1311032Y359874D01*
X1312138Y359638D01*
X1312915Y358443D01*
X1312679Y357337D01*
X1313456Y356142D01*
X1314562Y355906D01*
X1315338Y354711D01*
X1315103Y353605D01*
X1348937Y301507D01*
X1356663Y265176D01*
X1397775Y71840D01*
Y69251D01*
G03X1398376Y68650I601J0D01*
G01X1399613D01*
G01X1127703Y698797D02*
X1129052D01*
G02X1129796Y698053I0J-744D01*
G01Y696853D01*
G03X1132058Y694591I2262J0D01*
G01X1135259D01*
X1169876Y672108D01*
X1194809Y633721D01*
X1225552Y489063D01*
X1347692Y300991D01*
X1396450Y71700D01*
Y69250D01*
G02X1395850Y68650I-600J0D01*
G01X1394613D01*
G01X1129278Y705884D02*
X1127928D01*
G03X1127184Y705140I0J-744D01*
G01Y703940D01*
G03X1128121Y703003I937J0D01*
G01X1141752D01*
X1185173Y674808D01*
X1201484Y649689D01*
X1232097Y505648D01*
X1485622Y129786D01*
X1486733Y129570D01*
X1487530Y128389D01*
X1487314Y127278D01*
X1488111Y126097D01*
X1489221Y125881D01*
X1490018Y124699D01*
X1489802Y123589D01*
X1490599Y122407D01*
X1491710Y122192D01*
X1492507Y121010D01*
X1492291Y119900D01*
X1521235Y76988D01*
X1521987Y73118D01*
Y69201D01*
G03X1522538Y68650I551J0D01*
G01X1523825D01*
G01X1123766Y705884D02*
X1125115D01*
G02X1125859Y705140I0J-744D01*
G01Y703940D01*
G03X1128121Y701678I2262J0D01*
G01X1141359D01*
X1184215Y673850D01*
X1200239Y649173D01*
X1230854Y505121D01*
X1519985Y76471D01*
X1520662Y72990D01*
Y69200D01*
G02X1520112Y68650I-550J0D01*
G01X1518825D01*
G01X1133215Y712970D02*
X1131865D01*
G03X1131121Y712226I0J-744D01*
G01Y711026D01*
G03X1132058Y710089I937J0D01*
G01X1142502D01*
X1189483Y679581D01*
X1208487Y650315D01*
X1238727Y508047D01*
X1423604Y233957D01*
X1484163Y193670D01*
X1485272Y193893D01*
X1486458Y193104D01*
X1486681Y191995D01*
X1487868Y191205D01*
X1488977Y191428D01*
X1490163Y190639D01*
X1490386Y189530D01*
X1491573Y188740D01*
X1492682Y188963D01*
X1493868Y188174D01*
X1494091Y187065D01*
X1632361Y95080D01*
X1645733Y74483D01*
X1646200Y72287D01*
Y69201D01*
G03X1646751Y68650I551J0D01*
G01X1648038D01*
G01X1127703Y712970D02*
X1129052D01*
G02X1129796Y712226I0J-744D01*
G01Y711026D01*
G03X1132058Y708764I2262J0D01*
G01X1142109D01*
X1188525Y678623D01*
X1188524D01*
X1207242Y649799D01*
X1237484Y507519D01*
X1422651Y232998D01*
X1631398Y94128D01*
X1644488Y73967D01*
X1644875Y72147D01*
Y69200D01*
G02X1644325Y68650I-550J0D01*
G01X1643038D01*
G01X1129278Y720057D02*
X1127928D01*
G03X1127184Y719313I0J-744D01*
G01Y718113D01*
G03X1128121Y717176I937J0D01*
G01X1142121D01*
X1196574Y681817D01*
X1218450Y648130D01*
X1247919Y509464D01*
X1249643Y507249D01*
X1251366Y505033D01*
X1573705Y295705D01*
X1676951Y136057D01*
X1705022Y117828D01*
X1706129Y118063D01*
X1707324Y117287D01*
X1707559Y116180D01*
X1708754Y115404D01*
X1709861Y115639D01*
X1711056Y114863D01*
X1711291Y113756D01*
X1712486Y112980D01*
X1713593Y113216D01*
X1714788Y112439D01*
X1715023Y111333D01*
X1767415Y77309D01*
X1770412Y72658D01*
Y69201D01*
G03X1770963Y68650I551J0D01*
G01X1772250D01*
G01X1123766Y720057D02*
X1125115D01*
G02X1125859Y719313I0J-744D01*
G01Y718113D01*
G03X1128121Y715851I2262J0D01*
G01X1141728D01*
X1195616Y680859D01*
X1206409Y664237D01*
X1209106Y660083D01*
X1209107Y660084D01*
X1217205Y647614D01*
X1246623Y509188D01*
X1246686Y508891D01*
X1249458Y505327D01*
X1250457Y504043D01*
X1572745Y294747D01*
X1675991Y135099D01*
X1714301Y110221D01*
X1714300D01*
X1766455Y76352D01*
X1769087Y72268D01*
Y69200D01*
G02X1768537Y68650I-550J0D01*
G01X1767250D01*
G01X1133215Y727144D02*
X1131865D01*
G03X1131121Y726400I0J-744D01*
G01Y725200D01*
G03X1132058Y724263I937J0D01*
G01X1142475D01*
X1200676Y686465D01*
X1229478Y642111D01*
X1248382Y553182D01*
X1267154Y510078D01*
X1374388Y440442D01*
X1375550Y440689D01*
X1376745Y439913D01*
X1376992Y438751D01*
X1378187Y437975D01*
X1379349Y438222D01*
X1380544Y437446D01*
X1380791Y436284D01*
X1381986Y435508D01*
X1383148Y435755D01*
X1384343Y434978D01*
X1384590Y433816D01*
X1572452Y311820D01*
X1641500Y205482D01*
X1706133Y163510D01*
X1846920Y133583D01*
X1869684Y118800D01*
X1891822Y84715D01*
X1891955Y84510D01*
X1894625Y71952D01*
Y69275D01*
G03X1895250Y68650I625J0D01*
G01X1896463D01*
G01X1127703Y727144D02*
X1129052D01*
G02X1129796Y726400I0J-744D01*
G01Y725200D01*
G03X1132058Y722938I2262J0D01*
G01X1142082D01*
X1199718Y685507D01*
X1228233Y641595D01*
X1247113Y552775D01*
X1266098Y509183D01*
X1383868Y432704D01*
X1383867D01*
X1571494Y310862D01*
X1640542Y204524D01*
X1705617Y162265D01*
X1846404Y132338D01*
X1868726Y117842D01*
X1890710Y83994D01*
X1893300Y71812D01*
Y69200D01*
G02X1892750Y68650I-550J0D01*
G01X1891463D01*
G01X1129278Y776750D02*
X1128067D01*
G03X1127184Y775867I0J-883D01*
G01Y774867D01*
G03X1128182Y773869I998J0D01*
G01X1141612D01*
X1163325Y762636D01*
X1239507Y639912D01*
X1253778Y595279D01*
X1254784Y594760D01*
X1255217Y593403D01*
X1254699Y592398D01*
X1255133Y591040D01*
X1256139Y590522D01*
X1256573Y589165D01*
X1256054Y588159D01*
X1256488Y586802D01*
X1257494Y586283D01*
X1257928Y584926D01*
X1257410Y583920D01*
X1273562Y533403D01*
Y522038D01*
G03X1274194Y521406I632J0D01*
G01X1275400D01*
G01X1123766Y776750D02*
X1124976D01*
G02X1125859Y775867I0J-883D01*
G01Y774867D01*
G03X1128182Y772544I2323J0D01*
G01X1141289D01*
X1162391Y761626D01*
X1238294Y639352D01*
X1272237Y533196D01*
Y522037D01*
G02X1271606Y521406I-631J0D01*
G01X1270400D01*
G01X1133215Y783836D02*
X1132004D01*
G03X1131121Y782953I0J-883D01*
G01Y781953D01*
G03X1132119Y780955I998J0D01*
G01X1139829D01*
X1228012Y749451D01*
X1235862Y743797D01*
X1350739Y588755D01*
X1351859Y588589D01*
X1352707Y587444D01*
X1352540Y586325D01*
X1353389Y585180D01*
X1354508Y585013D01*
X1355356Y583868D01*
X1355190Y582749D01*
X1356038Y581604D01*
X1357157Y581438D01*
X1358005Y580293D01*
X1357839Y579174D01*
X1397775Y525274D01*
Y522051D01*
G03X1398420Y521406I645J0D01*
G01X1399613D01*
G01X1127703Y783836D02*
X1128913D01*
G02X1129796Y782953I0J-883D01*
G01Y781953D01*
G03X1132119Y779630I2323J0D01*
G01X1139599D01*
X1227390Y748266D01*
X1234920Y742842D01*
X1396450Y524836D01*
Y522050D01*
G02X1395806Y521406I-644J0D01*
G01X1394613D01*
G01X1129278Y790923D02*
X1128067D01*
G03X1127184Y790040I0J-883D01*
G01Y789040D01*
G03X1128182Y788042I998J0D01*
G01X1146614D01*
X1315740Y759946D01*
X1413995Y696140D01*
X1444909Y648520D01*
X1444910D01*
X1446016Y648284D01*
X1446792Y647089D01*
X1446557Y645983D01*
X1447333Y644787D01*
X1448439Y644552D01*
X1449215Y643357D01*
X1448980Y642250D01*
X1449756Y641055D01*
X1450862Y640819D01*
X1451638Y639624D01*
X1451403Y638518D01*
Y638517D01*
X1521681Y530259D01*
X1521987Y528823D01*
Y521963D01*
G03X1522544Y521406I557J0D01*
G01X1523825D01*
G01X1123766Y790923D02*
X1124976D01*
G02X1125859Y790040I0J-883D01*
G01Y789040D01*
G03X1128182Y786717I2323J0D01*
G01X1146504D01*
X1315250Y758684D01*
X1413037Y695182D01*
X1520436Y529743D01*
X1520662Y528683D01*
Y521962D01*
G02X1520106Y521406I-556J0D01*
G01X1518825D01*
G01X1133215Y798010D02*
X1132004D01*
G03X1131121Y797127I0J-883D01*
G01Y796127D01*
G03X1132119Y795129I998J0D01*
G01X1135489D01*
X1325002Y764415D01*
X1593597Y589984D01*
X1594703Y590219D01*
X1595898Y589443D01*
X1596134Y588336D01*
X1597329Y587560D01*
X1598435Y587795D01*
X1599630Y587019D01*
X1599866Y585912D01*
X1601061Y585136D01*
X1602167Y585371D01*
X1603362Y584595D01*
X1603598Y583489D01*
X1615592Y575699D01*
X1646200Y528539D01*
Y522200D01*
G03X1646994Y521406I794J0D01*
G01X1648038D01*
G01X1127703Y798010D02*
X1128913D01*
G02X1129796Y797127I0J-883D01*
G01Y796127D01*
G03X1132119Y793804I2323J0D01*
G01X1135382D01*
X1324514Y763151D01*
X1614634Y574741D01*
X1644875Y528146D01*
Y522200D01*
G02X1644081Y521406I-794J0D01*
G01X1643038D01*
G01X1129278Y805096D02*
X1128067D01*
G03X1127184Y804213I0J-883D01*
G01Y803213D01*
G03X1128182Y802215I998J0D01*
G01X1177269D01*
X1254165Y793006D01*
X1374261Y767479D01*
X1450405Y718031D01*
X1451511Y718266D01*
X1452706Y717490D01*
X1452942Y716383D01*
X1454137Y715607D01*
X1455243Y715842D01*
X1456438Y715066D01*
X1456674Y713960D01*
X1457869Y713183D01*
X1458975Y713419D01*
X1460171Y712643D01*
X1460406Y711536D01*
X1631745Y600267D01*
X1686025Y588729D01*
X1760063Y540653D01*
X1770412Y524725D01*
Y521988D01*
G03X1770994Y521406I582J0D01*
G01X1772250D01*
G01X1123766Y805096D02*
X1124976D01*
G02X1125859Y804213I0J-883D01*
G01Y803213D01*
G03X1128182Y800890I2323J0D01*
G01X1177189D01*
X1253948Y791697D01*
X1373745Y766234D01*
X1631229Y599022D01*
X1685509Y587484D01*
X1759105Y539695D01*
X1769087Y524332D01*
Y521987D01*
G02X1768506Y521406I-581J0D01*
G01X1767250D01*
G01X1133215Y812183D02*
X1132004D01*
G03X1131121Y811300I0J-883D01*
G01Y810300D01*
G03X1132119Y809302I998J0D01*
G01X1178498D01*
X1216097Y804265D01*
X1253661Y799232D01*
X1384104Y771504D01*
X1493814Y701551D01*
X1592891Y637212D01*
X1600955Y635498D01*
X1601904Y636114D01*
X1603297Y635818D01*
X1603914Y634869D01*
X1605308Y634573D01*
X1606256Y635189D01*
X1607650Y634893D01*
X1608266Y633944D01*
X1609660Y633648D01*
X1610609Y634264D01*
X1612003Y633967D01*
X1612619Y633019D01*
X1821618Y588594D01*
X1884585Y547704D01*
X1894625Y532244D01*
Y521901D01*
G03X1895120Y521406I495J0D01*
G01X1896463D01*
G01X1127703Y812183D02*
X1128913D01*
G02X1129796Y811300I0J-883D01*
G01Y810300D01*
G03X1132119Y807977I2323J0D01*
G01X1178409D01*
X1253435Y797925D01*
X1383594Y770257D01*
X1493096Y700436D01*
X1592375Y635967D01*
X1821102Y587349D01*
X1883627Y546746D01*
X1893300Y531851D01*
Y521900D01*
G02X1892806Y521406I-494J0D01*
G01X1891463D01*
G01X1133215Y868876D02*
X1131845D01*
G02X1131121Y869600I0J724D01*
G01Y870600D01*
G02X1132278Y871757I1157J0D01*
G01X1146283D01*
X1596192Y914387D01*
X1731240Y965195D01*
X1732270Y964728D01*
X1733604Y965230D01*
X1734071Y966260D01*
X1735405Y966762D01*
X1736435Y966295D01*
X1737769Y966797D01*
X1738236Y967827D01*
X1739570Y968329D01*
X1740601Y967862D01*
X1741934Y968364D01*
X1742401Y969395D01*
X1767049Y978668D01*
X1770350D01*
G02X1770825Y978193I0J-475D01*
G01Y976831D01*
G01X1127703Y868876D02*
X1129072D01*
G03X1129796Y869600I0J724D01*
G01Y870600D01*
G02X1132278Y873082I2482J0D01*
G01X1146212D01*
X1595889Y915690D01*
X1741934Y970635D01*
X1741933Y970636D01*
X1766808Y979993D01*
X1770350D01*
G03X1770825Y980468I0J475D01*
G01Y981831D01*
G01X1129278Y861789D02*
X1127995D01*
G02X1127184Y862600I0J811D01*
G01Y863600D01*
G02X1128254Y864670I1070J0D01*
G01X1149140D01*
X1728728Y908222D01*
X1744472Y912522D01*
X1756001Y915671D01*
X1783164Y923090D01*
X1827103Y936285D01*
X1828099Y935749D01*
X1829464Y936159D01*
X1830000Y937155D01*
X1831365Y937565D01*
X1832361Y937029D01*
X1833726Y937439D01*
X1834262Y938435D01*
X1835627Y938845D01*
X1836623Y938309D01*
X1837988Y938719D01*
X1838524Y939715D01*
X1839889Y940125D01*
X1861017Y952217D01*
X1876538Y973400D01*
X1881735Y976035D01*
X1886930Y978668D01*
X1894301D01*
G02X1895038Y977931I0J-737D01*
G01Y976831D01*
G01X1123766Y861789D02*
X1125048D01*
G03X1125859Y862600I0J811D01*
G01Y863600D01*
G02X1128254Y865995I2395J0D01*
G01X1149081D01*
X1728502Y909534D01*
X1732591Y910651D01*
X1755652Y916950D01*
X1782799Y924364D01*
X1839362Y941351D01*
X1860114Y953228D01*
X1875656Y974439D01*
X1881136Y977217D01*
X1886613Y979993D01*
X1894300D01*
G03X1895038Y980731I0J738D01*
G01Y981831D01*
G01X1133215Y897222D02*
X1131899D01*
G02X1131121Y898000I0J778D01*
G01Y898900D01*
G02X1132324Y900103I1203J0D01*
G01X1145845D01*
X1224403Y951118D01*
X1225510Y950883D01*
X1226705Y951659D01*
X1226940Y952766D01*
X1228136Y953542D01*
X1229242Y953307D01*
X1230437Y954083D01*
X1230673Y955190D01*
X1231868Y955966D01*
X1232974Y955730D01*
X1234169Y956507D01*
X1234405Y957613D01*
X1266826Y978668D01*
X1273500D01*
G02X1273975Y978193I0J-475D01*
G01Y976831D01*
G01X1127703Y897222D02*
X1129018D01*
G03X1129796Y898000I0J778D01*
G01Y898900D01*
G02X1132324Y901428I2528J0D01*
G01X1145452D01*
X1266433Y979993D01*
X1273500D01*
G03X1273975Y980468I0J475D01*
G01Y981831D01*
G01X1129278Y890136D02*
X1128148D01*
G02X1127184Y891100I0J964D01*
G01Y891900D01*
G02X1128301Y893017I1117J0D01*
G01X1144036D01*
X1201816Y907928D01*
X1259542Y922825D01*
X1360225Y967186D01*
X1361279Y966776D01*
X1362583Y967351D01*
X1362993Y968405D01*
X1364297Y968980D01*
X1365351Y968570D01*
X1366655Y969145D01*
X1367065Y970199D01*
X1368369Y970774D01*
X1369423Y970365D01*
X1370727Y970939D01*
X1371137Y971994D01*
X1386284Y978668D01*
X1397713D01*
G02X1398188Y978193I0J-475D01*
G01Y976831D01*
G01X1123766Y890136D02*
X1124895D01*
G03X1125859Y891100I0J964D01*
G01Y891900D01*
G02X1128301Y894342I2442J0D01*
G01X1143867D01*
X1259102Y924080D01*
X1386005Y979993D01*
X1397713D01*
G03X1398188Y980468I0J475D01*
G01Y981831D01*
G01X1133215Y883049D02*
X1131872D01*
G02X1131121Y883800I0J751D01*
G01Y884651D01*
G02X1132400Y885930I1279J0D01*
G01X1148056D01*
X1356090Y925190D01*
X1357025Y924552D01*
X1358425Y924817D01*
X1359063Y925751D01*
X1360463Y926015D01*
X1361398Y925377D01*
X1362798Y925642D01*
X1363436Y926576D01*
X1364836Y926840D01*
X1365817Y926171D01*
X1367218Y926435D01*
X1367887Y927416D01*
X1403801Y934194D01*
X1513792Y978668D01*
X1521601D01*
G02X1522400Y977869I0J-799D01*
G01Y976831D01*
G01X1127703Y883049D02*
X1129046D01*
G03X1129796Y883799I0J750D01*
G01Y884651D01*
G02X1132400Y887255I2604J0D01*
G01X1147932D01*
X1394480Y933784D01*
X1403426Y935472D01*
X1513534Y979993D01*
X1521600D01*
G03X1522400Y980793I0J800D01*
G01Y981831D01*
G01X1129278Y875962D02*
X1127922D01*
G02X1127184Y876700I0J738D01*
G01Y877700D01*
G02X1128327Y878843I1143J0D01*
G01X1146721D01*
X1508928Y926876D01*
X1602536Y962880D01*
X1603569Y962420D01*
X1604900Y962932D01*
X1605359Y963965D01*
X1606689Y964477D01*
X1607723Y964018D01*
X1609053Y964529D01*
X1609512Y965563D01*
X1610842Y966075D01*
X1611876Y965615D01*
X1613206Y966127D01*
X1613665Y967160D01*
X1643584Y978668D01*
X1646138D01*
G02X1646613Y978193I0J-475D01*
G01Y976831D01*
G01X1123766Y875962D02*
X1125121D01*
G03X1125859Y876700I0J738D01*
G01Y877700D01*
G02X1128327Y880168I2468J0D01*
G01X1146633D01*
X1327616Y904169D01*
X1508598Y928170D01*
X1643337Y979993D01*
X1646138D01*
G03X1646613Y980468I0J475D01*
G01Y981831D01*
G54D13*
X384055Y1330472D03*
Y1320472D03*
X354055Y1330472D03*
X364055D03*
X354055Y1320472D03*
X364055D03*
X324055Y1330472D03*
X334055D03*
X324055Y1320472D03*
X334055D03*
X304055Y1330472D03*
Y1320472D03*
X294055Y1330472D03*
Y1320472D03*
X384055Y1340472D03*
Y1350472D03*
X354055Y1340472D03*
Y1350472D03*
X364055Y1340472D03*
Y1350472D03*
X324055Y1340472D03*
Y1350472D03*
X334055Y1340472D03*
Y1350472D03*
X304055D03*
Y1340472D03*
X294055Y1350472D03*
Y1340472D03*
X474055Y1330472D03*
X484055D03*
X474055Y1320472D03*
X484055D03*
X444055Y1330472D03*
X454055D03*
X444055Y1320472D03*
X454055D03*
X414055Y1330472D03*
X424055D03*
X414055Y1320472D03*
X424055D03*
X394055Y1330472D03*
Y1320472D03*
X474055Y1340472D03*
Y1350472D03*
X484055Y1340472D03*
Y1350472D03*
X444055Y1340472D03*
Y1350472D03*
X454055Y1340472D03*
Y1350472D03*
X414055Y1340472D03*
Y1350472D03*
X424055Y1340472D03*
Y1350472D03*
X394055Y1340472D03*
Y1350472D03*
G54D23*
G01X46442Y825000D02*
X59474Y838032D01*
X171032D01*
X197439Y864439D01*
X788902D01*
X819208Y834133D01*
X900198D01*
X916750Y817581D01*
X919461D01*
X924484Y812558D01*
G01X151200Y48500D02*
X152900D01*
X166113Y35287D01*
X193167D01*
X204796Y23658D01*
X708135D01*
X711352Y26875D01*
G01X151200Y44400D02*
X152400D01*
X164765Y32035D01*
X191819D01*
X203448Y20406D01*
X708599D01*
X715205Y27012D01*
G01X921047Y811463D02*
X920057D01*
X899112Y832408D01*
X818493D01*
X788187Y862714D01*
X198214D01*
X169442Y833942D01*
Y824700D01*
G01X294542Y825000D02*
X309000D01*
X344989Y860989D01*
X787472D01*
X817778Y830683D01*
X897106D01*
X916855Y810934D01*
G01X913059Y810367D02*
X894468Y828958D01*
X817063D01*
X786757Y859264D01*
X462264D01*
X427444Y824444D01*
X418742D01*
G01X931800Y791500D02*
X923858D01*
X912333Y779975D01*
X902575D01*
X897825Y775225D01*
Y769985D01*
X875409Y747569D01*
X798212D01*
X779868Y729225D01*
X761625D01*
X708000Y675600D01*
X677100D01*
X666900Y665400D01*
G01X869989Y818847D02*
X869266Y819570D01*
X823765D01*
X821875Y821460D01*
X805975D01*
X794337Y809822D01*
Y800920D01*
X750428Y757011D01*
X724261D01*
X646680Y679430D01*
G01X582648Y825223D02*
X614964Y857539D01*
X786042D01*
X816348Y827233D01*
X891880D01*
X905506Y813607D01*
Y813444D01*
X906166Y812784D01*
G01X902560Y813313D02*
X901800D01*
X889605Y825508D01*
X815633D01*
X785327Y855814D01*
X681814D01*
X659642Y833642D01*
Y824700D01*
G01X628500Y1468500D02*
X639900Y1479900D01*
X706786D01*
X716953Y1469733D01*
X738767D01*
X745000Y1463500D01*
Y1463000D01*
G01X934800Y795300D02*
X925218D01*
X911718Y781800D01*
X901500D01*
X896100Y776400D01*
Y770700D01*
X874694Y749294D01*
X797496D01*
X790078Y741876D01*
Y741875D01*
X779153Y730950D01*
X754575D01*
X709871Y686246D01*
G01X909144Y803346D02*
Y799944D01*
X909094Y799894D01*
Y799888D01*
X905864Y796658D01*
X900658D01*
X895174Y791174D01*
X789471D01*
X751593Y753296D01*
X727116D01*
X720600Y746780D01*
Y741000D01*
X718100Y738500D01*
G01X903700Y803200D02*
X893400Y792900D01*
X788757D01*
X751143Y755286D01*
X726666D01*
X718200Y746820D01*
Y744000D01*
G01X912762Y792801D02*
X911356Y791395D01*
X901395D01*
X897724Y787724D01*
X790901D01*
X753023Y749846D01*
X729635D01*
X725700Y745911D01*
Y741900D01*
X723000Y739200D01*
G01X903221Y793938D02*
X901233D01*
X896744Y789449D01*
X790186D01*
X752308Y751571D01*
X728920D01*
X723974Y746625D01*
Y744374D01*
X723300Y743700D01*
G01X912030Y787650D02*
Y786330D01*
X909225Y783525D01*
X791582D01*
X754453Y746396D01*
X733271D01*
X728175Y741300D01*
G01X907800Y788700D02*
X907200Y789300D01*
X902100D01*
X898799Y785999D01*
X791616D01*
X753738Y748121D01*
X730721D01*
X728100Y745500D01*
G01X701700Y872700D02*
X717700D01*
X723233Y878233D01*
X801236D01*
X807757Y871712D01*
X828658D01*
X833989Y866381D01*
X886825D01*
X887838Y867394D01*
X892329D01*
X894317Y865406D01*
G01X890117D02*
X888290D01*
X887540Y864656D01*
X833274D01*
X827943Y869987D01*
X807042D01*
X800521Y876508D01*
X723948D01*
X718415Y870975D01*
X715375D01*
X714500Y870100D01*
G01X723600Y872400D02*
X725983Y874783D01*
X799806D01*
X806327Y868262D01*
X827228D01*
X832559Y862931D01*
X888255D01*
X888518Y863194D01*
X892329D01*
X894317Y861206D01*
G01X890117D02*
X831844D01*
X826513Y866537D01*
X805612D01*
X799091Y873058D01*
X728358D01*
X727600Y872300D01*
G01X754000Y884524D02*
X757224Y881300D01*
X805541D01*
X812038Y874803D01*
X853212D01*
X855767Y877358D01*
X879612D01*
X879667Y877303D01*
G01X757600Y884400D02*
X757989Y884789D01*
X805694D01*
X813105Y877378D01*
X852145D01*
X854700Y879933D01*
X882157D01*
X884684Y877406D01*
G01X724066Y1461018D02*
X736982D01*
X739662Y1458338D01*
X796670D01*
X819904Y1481572D01*
X996968D01*
X1006808Y1491412D01*
X1037737D01*
X1062659Y1466490D01*
Y1411141D01*
X1089788Y1384012D01*
Y1271888D01*
X1052615Y1234715D01*
Y1027731D01*
X1104600Y975746D01*
Y967800D01*
G01X724255Y1457253D02*
X736747D01*
X738237Y1455763D01*
X797737D01*
X817909Y1475935D01*
X938186D01*
X941248Y1478997D01*
X998035D01*
X1007875Y1488837D01*
X1036670D01*
X1060084Y1465423D01*
Y1409621D01*
X1087213Y1382492D01*
Y1272955D01*
X1049828Y1235570D01*
Y1026876D01*
X1101950Y974754D01*
Y962900D01*
G01X835165Y470414D02*
X835209Y470458D01*
X852958D01*
X928000Y545500D01*
X935511D01*
X940511Y550500D01*
X999000D01*
X1035975Y587475D01*
X1166025D01*
X1167000Y586500D01*
G01X848799Y457202D02*
X858750D01*
X916185Y514637D01*
X938924D01*
X944387Y520100D01*
G01X849539Y453596D02*
X858786D01*
X917252Y512062D01*
X939991D01*
X949947Y522018D01*
X991538D01*
G01X941557Y547005D02*
X937052Y542500D01*
X931200D01*
X875188Y486488D01*
Y486477D01*
X874023Y485312D01*
X874012D01*
X856162Y467462D01*
X829970D01*
X827313Y464805D01*
G01X827361Y459317D02*
X832049Y464005D01*
X857405D01*
X931400Y538000D01*
X957400D01*
X961400Y542000D01*
X978000D01*
X983651Y547651D01*
X1000044D01*
X1000051Y547644D01*
G01X832417Y459017D02*
X834830Y461430D01*
X858930D01*
X929200Y531700D01*
X975800D01*
X985643Y541543D01*
X997743D01*
X1041100Y584900D01*
X1138900D01*
G01X1103770Y675413D02*
X1107896D01*
X1151824Y631485D01*
Y596826D01*
X1146000Y591002D01*
X1035860D01*
X998811Y553953D01*
X932811D01*
X898035Y519177D01*
X884906D01*
X863710Y497981D01*
Y491400D01*
X858740Y486430D01*
G01X794883Y639984D02*
X794886D01*
X796631Y638239D01*
X799298D01*
X799559Y638500D01*
X810280D01*
X819380Y629400D01*
X872430D01*
X873255Y630225D01*
X884801D01*
G01X798475Y640227D02*
X799998Y641750D01*
X809840D01*
X817890Y633700D01*
X892400D01*
G01X874593Y763800D02*
X873524Y764869D01*
X832767D01*
X824591Y756693D01*
X800903D01*
X779854Y735644D01*
X778627D01*
G01X874821Y767690D02*
X831946D01*
X823524Y759268D01*
X792902D01*
X778683Y745049D01*
G01X870001Y822862D02*
X868639Y821500D01*
X824275D01*
X822255Y823520D01*
X815181D01*
X798813Y839888D01*
X778735D01*
G01X876862Y842155D02*
X875368Y843649D01*
X842191D01*
X828100Y857740D01*
Y859840D01*
X825900Y862040D01*
G01X881702Y838859D02*
X863778D01*
X860713Y841924D01*
X841476D01*
X826000Y857400D01*
G01X931380Y821500D02*
X929456Y819576D01*
Y809600D01*
X928176Y808320D01*
X905865D01*
X905835Y808350D01*
X902940D01*
X899703Y811587D01*
X869008D01*
X867583Y813012D01*
X832570D01*
X830587Y811029D01*
X815469D01*
G01X815330Y807050D02*
X816618Y808338D01*
X831538D01*
X833637Y810437D01*
X866516D01*
X867941Y809012D01*
X898636D01*
X901873Y805775D01*
X904768D01*
X904798Y805745D01*
X929337D01*
X933392Y809800D01*
Y819307D01*
X935485Y821400D01*
G01X1113530Y854703D02*
X1110975Y857258D01*
X1092111D01*
X1091355Y856502D01*
X1044698D01*
X1037300Y863900D01*
X961100D01*
X956295Y868705D01*
X947605D01*
X939700Y860800D01*
X911559D01*
X899559Y848800D01*
X875785D01*
X873269Y846284D01*
X859084D01*
X858500Y845700D01*
G01X1119042Y854703D02*
X1114482Y859263D01*
X1073954D01*
X1066417Y866800D01*
X961889D01*
X957409Y871280D01*
X946538D01*
X939258Y864000D01*
X911117D01*
X898492Y851375D01*
X874718D01*
X873043Y849700D01*
X858400D01*
X858100Y850000D01*
G01X848300Y847700D02*
X859100Y858500D01*
X895300D01*
X909092Y872292D01*
Y872293D01*
X910399Y873600D01*
X939133D01*
X943688Y878155D01*
X963787D01*
X967942Y874000D01*
X1029100D01*
X1032900Y877800D01*
X1053700D01*
X1056000Y875500D01*
X1079300D01*
X1081351Y873449D01*
X1107080D01*
X1109593Y875962D01*
G01X1113530Y897222D02*
X1111005Y894697D01*
X1092215D01*
X1091417Y895495D01*
X1072635D01*
X1065918Y888778D01*
X1000637D01*
X1000452Y888963D01*
X984037D01*
X980425Y892575D01*
X974771D01*
X968776Y886580D01*
X951488D01*
X944023Y894045D01*
X873255D01*
X869528Y897772D01*
X846670D01*
X844800Y895902D01*
G01X1119042Y897222D02*
X1114483Y892663D01*
X1073445D01*
X1066985Y886203D01*
X1001703D01*
X996412Y880912D01*
X971478D01*
X968385Y884005D01*
X941305D01*
X940000Y882700D01*
X883772D01*
X880948Y885524D01*
X857376D01*
X851187Y891713D01*
X845732D01*
G01X772361Y1451972D02*
Y1451822D01*
X797438D01*
X818867Y1473251D01*
X939144D01*
X942315Y1476422D01*
X999102D01*
X1007855Y1485175D01*
X1036690D01*
X1049260Y1472605D01*
Y1466691D01*
G01X911811Y253937D02*
X925800Y267926D01*
Y325823D01*
X995465Y395488D01*
X1038806D01*
X1084028Y440710D01*
X1133110D01*
X1160900Y468500D01*
G01X904725Y262992D02*
X909281Y267548D01*
Y317974D01*
X992820Y401513D01*
X1032313D01*
X1094204Y463404D01*
X1152162D01*
X1156110Y467352D01*
Y473330D01*
G01X904725Y268504D02*
X907306Y271085D01*
Y318439D01*
X992105Y403238D01*
X1031598D01*
X1093935Y465575D01*
X1149705D01*
X1152600Y468470D01*
G01X897638Y272441D02*
X902184Y276987D01*
Y314686D01*
X901920Y314950D01*
Y319843D01*
X903994Y321917D01*
Y332206D01*
X909560Y337772D01*
Y354256D01*
X909423Y354393D01*
G01X897638Y277953D02*
X893116Y282475D01*
Y318061D01*
X894127Y319072D01*
Y335960D01*
X898059Y339892D01*
Y343029D01*
G01X897638Y282283D02*
X895091Y284830D01*
Y312465D01*
X897103Y314477D01*
Y335991D01*
X902184Y341072D01*
Y347219D01*
G01X911811Y272441D02*
X919600Y280230D01*
Y323265D01*
X994398Y398063D01*
X1034097D01*
X1087240Y451206D01*
X1127394D01*
X1131800Y446800D01*
G01X911811Y277953D02*
X916300Y282442D01*
Y322463D01*
X993625Y399788D01*
X1033028D01*
X1086170Y452930D01*
X1086524D01*
X1086525Y452931D01*
X1129918D01*
X1136000Y446849D01*
G01X904725Y315354D02*
Y318298D01*
X991390Y404963D01*
X1030883D01*
X1093221Y467301D01*
X1125201D01*
X1130800Y472900D01*
G01X897638Y286614D02*
X900209Y289185D01*
Y313174D01*
X899077Y314306D01*
Y320657D01*
X901245Y322825D01*
Y332789D01*
X906712Y338256D01*
Y351490D01*
X906616Y351586D01*
G01X890552Y305512D02*
X888038Y308026D01*
Y316542D01*
X892089Y320593D01*
Y336801D01*
X896071Y340783D01*
Y344079D01*
X936148Y384156D01*
X959989D01*
X988097Y412264D01*
X1027736D01*
X1090623Y475151D01*
X1103072D01*
X1114184Y486263D01*
X1119269D01*
X1183077Y550071D01*
Y592065D01*
X1177350Y597792D01*
G01X935490Y519550D02*
X944879Y528939D01*
X986748D01*
X992897Y535088D01*
X995342D01*
X1042030Y581776D01*
X1169125D01*
G01X903572Y773740D02*
X903600D01*
X903760Y773900D01*
X903858D01*
X904633Y774675D01*
X911433D01*
X925033Y788275D01*
X932001D01*
X937500Y793774D01*
Y839462D01*
X931206Y845756D01*
G01X920170Y857430D02*
Y856792D01*
X931206Y845756D01*
G01X939500Y842400D02*
X940075Y841825D01*
Y792707D01*
X933068Y785700D01*
X926100D01*
X917500Y777100D01*
Y776900D01*
X912575Y771975D01*
X906433D01*
X904358Y769900D01*
X903500D01*
G01X924670Y857430D02*
Y857230D01*
X939500Y842400D01*
G01X1039500Y874700D02*
X1033442D01*
X1030167Y871425D01*
X966875D01*
X962720Y875580D01*
X944755D01*
X939575Y870400D01*
X910842D01*
X896366Y855924D01*
X894234D01*
X894233Y855925D01*
X867480D01*
X866655Y855100D01*
G01X1119042Y868876D02*
X1115749Y865583D01*
X1083309D01*
X1082100Y864374D01*
X1072485D01*
X1067159Y869700D01*
X964900D01*
X960745Y873855D01*
X945471D01*
X943766Y872150D01*
X943765D01*
X939215Y867600D01*
X911075D01*
X897459Y853984D01*
X871981D01*
X870200Y852203D01*
G01X943294Y838833D02*
Y831808D01*
X947600Y827502D01*
Y796200D01*
X934400Y783000D01*
X927800D01*
X914200Y769400D01*
X907500D01*
X903300Y765200D01*
Y763200D01*
G01X991360Y529780D02*
X994093Y532513D01*
X996409D01*
X1042696Y578800D01*
X1166150D01*
X1166550Y579200D01*
G01X977676Y828513D02*
X978621Y827568D01*
X987134D01*
X988621Y829055D01*
Y831118D01*
X991412Y833909D01*
Y834073D01*
X992577Y835238D01*
X992741D01*
X997828Y840325D01*
X1002038D01*
X1005272Y837091D01*
G01X973070Y828512D02*
X976728Y824854D01*
X988062D01*
X1000280Y837072D01*
X1000827D01*
G01X1039500Y874700D02*
X1042775Y871425D01*
X1067874D01*
X1068720Y870579D01*
X1091232D01*
X1092127Y871474D01*
X1110932D01*
X1113530Y868876D01*
G01X1022080Y960728D02*
X1030862Y951946D01*
G01X1101600Y953700D02*
X1096751Y958549D01*
Y976311D01*
X1047128Y1025934D01*
Y1236512D01*
X1084638Y1274022D01*
Y1301207D01*
X1080092Y1305753D01*
Y1381727D01*
X1053948Y1407871D01*
Y1443004D01*
X1048553Y1448399D01*
G01X1201000Y447000D02*
X1193000D01*
X1164094Y475906D01*
X1121529D01*
X1120308Y474685D01*
X1115002D01*
X1113593Y476094D01*
G01X1107674Y677776D02*
X1108650D01*
X1156426Y630000D01*
Y602384D01*
X1175500Y583310D01*
Y554523D01*
X1114816Y493839D01*
X1110497D01*
X1103870Y487212D01*
X1102677D01*
Y487116D01*
G01X1119242Y477261D02*
X1120554Y478573D01*
X1165927D01*
X1192500Y452000D01*
X1200500D01*
G01X1118505Y658863D02*
X1134600Y642768D01*
Y618747D01*
G01X1129500Y619200D02*
Y644302D01*
X1114920Y658882D01*
X1114905D01*
G01X1068569Y1191530D02*
X1069347Y1192308D01*
Y1195531D01*
X1091586Y1217770D01*
Y1232413D01*
X1108586Y1249413D01*
X1230814D01*
X1293000Y1311599D01*
Y1420895D01*
X1277086Y1436809D01*
Y1447690D01*
X1280184Y1450788D01*
X1280884D01*
X1290662Y1460566D01*
Y1482612D01*
X1289574Y1483700D01*
G01X1676511Y1292495D02*
X1672004Y1287988D01*
X1273402D01*
X1233102Y1247688D01*
X1109302D01*
X1093312Y1231698D01*
Y1217056D01*
X1072931Y1196675D01*
Y1191482D01*
G01X1096280Y1288150D02*
Y1384930D01*
X1091000Y1390210D01*
Y1393500D01*
G01X1092475Y1287971D02*
X1093325Y1288821D01*
Y1384243D01*
X1086646Y1390922D01*
Y1396419D01*
G01X1261100Y16600D02*
X1263700Y19200D01*
X1780500D01*
X1798400Y37100D01*
Y51780D01*
X1803620Y57000D01*
G01X1264700Y16400D02*
X1781900D01*
X1801200Y35700D01*
Y50600D01*
X1807500Y56900D01*
Y57400D01*
G54D14*
X462000Y1382985D03*
Y1372985D03*
Y1362985D03*
X474000Y1382985D03*
Y1372985D03*
Y1362985D03*
X426000D03*
X450000Y1372985D03*
Y1382985D03*
X414000Y1372985D03*
X450000Y1362985D03*
X438000Y1372985D03*
X414000Y1362985D03*
X438000D03*
X426000Y1372985D03*
X438000Y1382985D03*
X414000D03*
X426000D03*
X498000Y1332985D03*
X510000Y1344485D03*
X498000Y1352985D03*
X522000Y1344485D03*
X498000Y1342985D03*
X510000Y1354485D03*
X522000D03*
X510000Y1364485D03*
X522000D03*
X510000Y1374485D03*
Y1384485D03*
X522000Y1374485D03*
Y1384485D03*
X498000Y1382985D03*
Y1372985D03*
X486000Y1382985D03*
Y1372985D03*
X498000Y1362985D03*
X486000D03*
X658200Y1329200D03*
X666100D03*
X581800Y1321200D03*
Y1329100D03*
X589700D03*
Y1321200D03*
X594800Y1313500D03*
X597600Y1321200D03*
Y1329100D03*
X610600Y1313500D03*
Y1305600D03*
Y1297600D03*
X602700Y1313500D03*
Y1305600D03*
Y1297600D03*
X629200Y1329100D03*
X605500Y1321200D03*
X613400D03*
X605500Y1329100D03*
X613400D03*
X621300D03*
X666100Y1360800D03*
Y1368700D03*
Y1376600D03*
Y1352900D03*
X658200Y1360800D03*
Y1368700D03*
Y1376600D03*
Y1352900D03*
X666100Y1337100D03*
Y1345000D03*
X658200Y1337100D03*
Y1345000D03*
X581800Y1376500D03*
Y1384400D03*
Y1392300D03*
Y1360700D03*
Y1368600D03*
Y1352800D03*
Y1344900D03*
Y1337000D03*
X589700Y1392300D03*
Y1400200D03*
Y1344900D03*
Y1352800D03*
Y1384400D03*
Y1376500D03*
Y1368600D03*
Y1360700D03*
Y1337000D03*
X597600Y1400200D03*
Y1408100D03*
Y1360700D03*
Y1368600D03*
Y1392300D03*
Y1376500D03*
Y1384400D03*
Y1352800D03*
Y1337000D03*
Y1344900D03*
X629200D03*
X621300D03*
X613400D03*
X605500D03*
Y1360700D03*
X613400D03*
X621300D03*
X629200D03*
X605500Y1352800D03*
X613400D03*
X621300D03*
X629200D03*
Y1368600D03*
Y1376500D03*
X605500Y1408100D03*
Y1400200D03*
Y1392300D03*
Y1384400D03*
Y1376500D03*
Y1368600D03*
X613400Y1400200D03*
Y1392300D03*
Y1384400D03*
Y1376500D03*
Y1368600D03*
X621300Y1376500D03*
Y1368600D03*
X629200Y1337000D03*
X613400D03*
X621300D03*
X605500D03*
X613400Y1408100D03*
X705600Y1329200D03*
X697700Y1321300D03*
Y1329200D03*
X689800D03*
Y1321300D03*
X693800Y1313900D03*
Y1306000D03*
X685900D03*
X678000D03*
Y1313900D03*
X685900D03*
X681900Y1321300D03*
X674000D03*
Y1329200D03*
X681900D03*
X693800Y1298000D03*
X685900D03*
X678000D03*
X768867Y1311110D03*
Y1335110D03*
Y1327110D03*
Y1319110D03*
X705600Y1337100D03*
Y1360800D03*
Y1352900D03*
Y1345000D03*
Y1376600D03*
Y1368700D03*
X699600Y1408200D03*
Y1392400D03*
Y1400300D03*
X697700Y1345000D03*
Y1360800D03*
Y1368700D03*
Y1376600D03*
X697100Y1384600D03*
X697700Y1352900D03*
Y1337100D03*
X691700Y1408200D03*
Y1400300D03*
X675900D03*
X683800D03*
Y1408200D03*
X675900D03*
X689800Y1352900D03*
Y1384500D03*
Y1376600D03*
X691700Y1392400D03*
X689800Y1368700D03*
Y1360800D03*
X674000D03*
X681900D03*
Y1368700D03*
X674000D03*
X675900Y1392400D03*
X683800D03*
X674000Y1376600D03*
X681900D03*
Y1384500D03*
X674000D03*
Y1352900D03*
X681900D03*
X689800Y1345000D03*
Y1337100D03*
X681900D03*
X674000D03*
X681900Y1345000D03*
X674000D03*
X768867Y1383110D03*
Y1359110D03*
Y1367110D03*
Y1351110D03*
Y1343110D03*
Y1391110D03*
Y1399110D03*
Y1375110D03*
X786200Y1334100D03*
X794200D03*
X801000Y1333800D03*
X786200Y1326100D03*
X794200D03*
X776867Y1311110D03*
Y1335110D03*
Y1327110D03*
Y1319110D03*
X775600Y1302400D03*
X801000Y1325800D03*
X790056Y1297863D03*
X798056D03*
X782056D03*
X776867Y1399110D03*
X790330Y1407929D03*
X782330D03*
X798330D03*
X795000Y1377900D03*
X786600Y1378100D03*
X790950Y1372703D03*
X776867Y1383110D03*
Y1359110D03*
X782950Y1372703D03*
X776867Y1367110D03*
Y1375110D03*
X798950Y1372703D03*
X776867Y1391110D03*
X790223Y1339930D03*
X782223Y1339430D03*
X798223Y1339930D03*
X776867Y1351110D03*
Y1343110D03*
X918000Y1376000D03*
X998600Y1300900D03*
X991500Y1312100D03*
X1020800Y1300400D03*
X991455Y1320416D03*
X996400Y1315900D03*
X996200Y1307800D03*
X1014000Y1300600D03*
X991755Y1327716D03*
X996055Y1324116D03*
X1007100Y1301100D03*
X1011100Y1305300D03*
X1019829Y1306139D03*
X1002700Y1305700D03*
X991800Y1303400D03*
X1000200Y1311700D03*
Y1320500D03*
X1016429Y1333939D03*
X1021829D03*
X1011029D03*
X1005629D03*
X986755Y1323816D03*
X986700Y1307600D03*
X1000200Y1328100D03*
X1050818Y1311189D03*
Y1316589D03*
X1045418Y1321989D03*
X1050818D03*
X1034618Y1311189D03*
X1040018D03*
X1045418D03*
X1040018Y1316589D03*
X1034618D03*
X1040018Y1321989D03*
X1031600Y1335100D03*
X1037200Y1335000D03*
X1034618Y1321989D03*
X997900Y1335800D03*
X992500D03*
X997900Y1341200D03*
X992500D03*
X997900Y1346600D03*
X992500D03*
X997900Y1352000D03*
X992500D03*
Y1357400D03*
X997900D03*
X989083Y1387764D03*
X989509Y1393422D03*
X994700Y1385000D03*
X999700Y1374500D03*
X989100Y1381700D03*
X994200Y1362700D03*
X1019829Y1389539D03*
X1013692Y1389688D03*
X1019829Y1361739D03*
X1014306Y1361710D03*
X1008870Y1361681D03*
X1003367Y1361655D03*
X1004217Y1389394D03*
X1008298Y1393071D03*
X994400Y1377300D03*
X999930Y1393070D03*
X999800Y1381600D03*
X999900Y1366800D03*
X994300Y1370100D03*
X989200Y1374800D03*
X988900Y1366900D03*
X1034600Y1349600D03*
X1042400Y1349500D03*
X1037540Y1344964D03*
X1034799Y1340183D03*
X1044700Y1335500D03*
X1043300Y1342500D03*
X1048000Y1346100D03*
X1037111Y1372380D03*
X1039988Y1367352D03*
X1044400Y1363100D03*
X1036900Y1362600D03*
X1034380Y1367469D03*
X1031300Y1362700D03*
X1042100Y1377100D03*
X1034300Y1377200D03*
X1047401Y1375084D03*
X1066481Y1327759D03*
X1061081D03*
X1066481Y1333159D03*
X1061081D03*
X1061618Y1316589D03*
X1056218Y1311189D03*
X1061618D03*
X1056218Y1316589D03*
X1060218Y1321989D03*
X1066491Y1319983D03*
X1066407Y1313972D03*
X1066481Y1338559D03*
X1061081D03*
X1066481Y1343959D03*
X1061081D03*
X1066481Y1376359D03*
Y1349359D03*
Y1354759D03*
Y1360159D03*
Y1365559D03*
Y1370959D03*
X1061081Y1376359D03*
Y1370959D03*
Y1365559D03*
Y1360159D03*
Y1354759D03*
Y1349359D03*
G54D15*
X862205Y263779D03*
X848032D03*
X833859D03*
X862205Y258268D03*
X848032D03*
X833859D03*
X862205Y253937D03*
X848032D03*
X833859D03*
X855118Y282677D03*
X840945D03*
X826772D03*
X855118Y277165D03*
X840945D03*
X826772D03*
X911811Y272441D03*
Y277953D03*
X904725Y262992D03*
Y268504D03*
X911811Y253937D03*
X897638Y282283D03*
Y272441D03*
Y277953D03*
X876378Y263779D03*
Y258268D03*
Y253937D03*
X869292Y282677D03*
Y277165D03*
X904725Y315354D03*
X897638Y286614D03*
X890552Y305512D03*
X1123766Y520057D03*
X1129278D03*
X1127703Y527143D03*
X1133215D03*
X1123766Y534230D03*
X1129278D03*
X1127703Y541317D03*
X1133215D03*
X1123766Y548403D03*
X1129278D03*
X1127703Y555490D03*
X1133215D03*
X1123766Y562576D03*
X1129278D03*
X1127703Y569663D03*
X1133215D03*
X1109593Y691711D03*
X1123766D03*
Y705884D03*
Y720057D03*
Y734230D03*
Y748403D03*
Y762577D03*
X1129278Y691711D03*
Y705884D03*
Y720057D03*
Y734230D03*
Y748403D03*
Y762577D03*
X1127703Y698797D03*
Y712970D03*
Y727144D03*
Y741317D03*
Y755490D03*
X1133215Y698797D03*
Y712970D03*
Y727144D03*
Y741317D03*
Y755490D03*
X1123766Y776750D03*
Y790923D03*
Y805096D03*
Y819270D03*
Y833443D03*
Y847616D03*
X1129278Y776750D03*
Y790923D03*
Y805096D03*
Y819270D03*
Y833443D03*
Y847616D03*
X1113530Y854703D03*
X1119042D03*
X1127703Y769663D03*
Y783836D03*
Y798010D03*
Y812183D03*
Y826356D03*
Y840529D03*
Y854703D03*
X1133215Y769663D03*
Y783836D03*
Y798010D03*
Y812183D03*
Y826356D03*
Y840529D03*
Y854703D03*
X1109593Y875962D03*
X1123766Y861789D03*
Y875962D03*
Y890136D03*
Y904309D03*
Y918482D03*
Y932655D03*
X1129278Y861789D03*
Y875962D03*
Y890136D03*
Y904309D03*
Y918482D03*
Y932655D03*
X1113530Y868876D03*
Y897222D03*
X1119042Y868876D03*
Y897222D03*
X1127703Y868876D03*
Y883049D03*
Y897222D03*
Y911396D03*
Y925569D03*
Y939742D03*
X1133215Y868876D03*
Y883049D03*
Y897222D03*
Y911396D03*
Y925569D03*
Y939742D03*
G54D16*
X1002362Y284449D03*
X1014960D03*
X1030709D03*
X1043307D03*
X1002362Y261812D03*
X1014960D03*
X1030709D03*
X1043307D03*
X1002362Y278544D03*
X1030709D03*
X1002362Y267717D03*
X1030709D03*
X1002362Y255906D03*
X1030709D03*
X1014960Y278544D03*
X1043307D03*
X1014960Y267717D03*
X1043307D03*
X1014960Y255906D03*
X1043307D03*
X1002362Y290355D03*
X1030709D03*
X1014960D03*
X1043307D03*
G54D17*
G01X113314Y1441700D02*
X113274Y1441660D01*
Y1308954D01*
X187228Y1235000D01*
X698800D01*
X764100Y1169700D01*
X776800D01*
G01X1078850Y1287900D02*
Y1292094D01*
X1073984Y1296960D01*
X1069432D01*
X1053067Y1280595D01*
X741295D01*
X713000Y1252300D01*
X186300D01*
X140774Y1297826D01*
Y1414918D01*
X127974Y1427718D01*
Y1462657D01*
X134317Y1469000D01*
X137624D01*
G01X136774Y1411000D02*
Y1297583D01*
X188757Y1245600D01*
X707000D01*
X709024Y1243576D01*
X709810D01*
X776777Y1176609D01*
Y1175823D01*
X805100Y1147500D01*
X832800D01*
G01X646102Y1321750D02*
X644700Y1323152D01*
Y1410590D01*
X654731Y1420621D01*
Y1454546D01*
X652777Y1456500D01*
X650948D01*
X650000Y1457448D01*
G01X641102Y1321750D02*
X642700Y1323348D01*
Y1411419D01*
X652731Y1421450D01*
Y1453717D01*
X651948Y1454500D01*
X650948D01*
X650000Y1453552D01*
G01X646200Y1420576D02*
X644700Y1422076D01*
Y1464000D01*
X645700Y1465000D01*
X649052D01*
X650000Y1464052D01*
G01Y1467948D02*
X649052Y1467000D01*
X644871D01*
X642700Y1464829D01*
Y1422076D01*
X641200Y1420576D01*
G01X636250Y1468500D02*
Y1471250D01*
X642112Y1477112D01*
X693388D01*
X697000Y1473500D01*
X709243D01*
X719119Y1463624D01*
Y1458649D01*
X723768Y1454000D01*
X736000D01*
X741397Y1448603D01*
X798860D01*
X819557Y1469300D01*
X939136D01*
X943470Y1473634D01*
X1024207D01*
X1032300Y1465541D01*
X1036525D01*
X1056737Y1445329D01*
Y1409025D01*
X1084280Y1381482D01*
Y1306780D01*
X1083100Y1305600D01*
G01X860360Y605900D02*
X858860D01*
X853968Y601008D01*
X793869D01*
X730300Y537439D01*
Y513800D01*
X714600Y498100D01*
G01X869937Y1400312D02*
Y1417083D01*
X845323Y1441697D01*
X728999D01*
X712615Y1458081D01*
Y1460355D01*
X703570Y1469400D01*
X693756D01*
X692000Y1471156D01*
G01X681250Y1433500D02*
X689250D01*
G01X708600Y1469900D02*
X715034Y1463466D01*
Y1458491D01*
X729828Y1443697D01*
X798197D01*
X820800Y1466300D01*
X1020756D01*
X1033253Y1453803D01*
Y1444649D01*
G01X791530Y614700D02*
Y615000D01*
X801530Y605000D01*
X854115D01*
X857615Y608500D01*
X867160D01*
X867260Y608600D01*
G01X791680Y619050D02*
X792200D01*
X794063Y617187D01*
X835443D01*
X838060Y614570D01*
X854270D01*
X857300Y611540D01*
X882630D01*
X883030Y611940D01*
G01X799900Y636300D02*
Y631990D01*
X811703Y620187D01*
X854103D01*
X859750Y614540D01*
X877540D01*
X878600Y615600D01*
G01X879600Y621600D02*
X879420Y621420D01*
X865370D01*
X863603Y623187D01*
X814163D01*
X807440Y629910D01*
G01X802900Y634000D02*
X803781Y633119D01*
X811718D01*
X818225Y626612D01*
X869460D01*
X869872Y626200D01*
X878400D01*
G01X836953Y1023500D02*
X969000D01*
X1017500Y975000D01*
Y952781D01*
X1024129Y946152D01*
G01X945408Y378761D02*
X948015Y381368D01*
X963852D01*
X990235Y407751D01*
X1029310D01*
X1036503Y414944D01*
X1036799D01*
X1092307Y470452D01*
X1104302D01*
X1115600Y481750D01*
X1123650D01*
X1187876Y545976D01*
Y548487D01*
X1187877Y548488D01*
Y552226D01*
X1187876Y552227D01*
Y599046D01*
X1186244Y600678D01*
X1186243D01*
X1168515Y618406D01*
Y646038D01*
X1141230Y673323D01*
Y673825D01*
G01X1112682Y681223D02*
X1113727D01*
X1159214Y635736D01*
Y603717D01*
X1178288Y584643D01*
Y557725D01*
X1178289Y557724D01*
Y555416D01*
X1178288Y555415D01*
Y552055D01*
X1117284Y491051D01*
X1111775D01*
X1100663Y479939D01*
X1088639D01*
X1050649Y441949D01*
X1038067D01*
Y441886D01*
G01X1109593Y691711D02*
X1161214Y640090D01*
Y605842D01*
X1180288Y586768D01*
Y558554D01*
X1180289Y558553D01*
Y554587D01*
X1180288Y554586D01*
Y551225D01*
X1118114Y489051D01*
X1112993D01*
X1101881Y477939D01*
X1089468D01*
X1051215Y439686D01*
X1021890D01*
Y439717D01*
G01X1075706Y941261D02*
X1029020D01*
X1024129Y946152D01*
G01X1093588Y972000D02*
Y975531D01*
X1044340Y1024779D01*
Y1237667D01*
X1081850Y1275177D01*
Y1296118D01*
X1077304Y1300664D01*
Y1379125D01*
X1051099Y1405330D01*
Y1433525D01*
X1039975Y1444649D01*
X1033253D01*
G01X965500Y1128000D02*
X978700Y1141200D01*
X1023143D01*
X1030178Y1134165D01*
G01X1029000Y1122400D02*
X1015800Y1135600D01*
X986100D01*
X982990Y1132490D01*
X977643D01*
G01X988693Y1421399D02*
X996693D01*
G01X1180614Y1340033D02*
X1152614D01*
X1148681Y1336100D01*
X1114300D01*
X1112200Y1334000D01*
Y1285300D01*
X1058403Y1231503D01*
Y1030543D01*
X1111100Y977846D01*
Y964700D01*
X1110600Y964200D01*
G01X1108500Y960600D02*
X1107700Y961400D01*
Y976988D01*
X1055403Y1029285D01*
Y1233403D01*
X1109200Y1287200D01*
Y1336000D01*
X1112500Y1339300D01*
X1141400D01*
X1153700Y1351600D01*
X1211645D01*
X1213820Y1349425D01*
Y1340033D01*
G01X1260574Y1445600D02*
X1289875Y1416299D01*
Y1312632D01*
X1229444Y1252201D01*
X1107431D01*
X1088798Y1233568D01*
Y1219698D01*
X1073600Y1204500D01*
X1072900D01*
G01X1800326Y1445800D02*
Y1381126D01*
X1701400Y1282200D01*
X1275800D01*
X1235500Y1241900D01*
X1111700D01*
X1099100Y1229300D01*
Y1214658D01*
X1084571Y1200129D01*
G01X1072600Y1211400D02*
X1075856D01*
X1085798Y1221342D01*
Y1234811D01*
X1106188Y1255201D01*
X1227444D01*
X1286874Y1314631D01*
Y1415057D01*
X1256474Y1445457D01*
Y1446000D01*
G01X1794426Y1446400D02*
Y1379726D01*
X1699900Y1285200D01*
X1274557D01*
X1234257Y1244900D01*
X1110457D01*
X1096100Y1230543D01*
Y1215901D01*
X1084400Y1204201D01*
Y1204200D01*
G01X1918800Y1112100D02*
X1193200D01*
X1155600Y1074500D01*
G01X1755159Y469723D02*
X1833787D01*
X1836476Y467034D01*
G54D18*
G01X139374Y1486100D02*
X143574Y1481900D01*
Y1458000D01*
X140364Y1454790D01*
Y1433129D01*
X150793Y1422700D01*
X165774D01*
G01X139374Y1486100D02*
X137774D01*
X134574Y1489300D01*
X116374D01*
X109174Y1482100D01*
Y1462190D01*
X104184Y1457200D01*
G01X1034254Y1182584D02*
X1031341Y1179671D01*
X953529D01*
X947700Y1185500D01*
G01X962136Y1431831D02*
X947928D01*
X945415Y1429318D01*
G01D02*
Y1412819D01*
X945414Y1412818D01*
G01D02*
X934118D01*
X923100Y1401800D01*
Y1381100D01*
X918000Y1376000D01*
G01X1058800Y893750D02*
X1044800D01*
G01X1087962Y959252D02*
Y976207D01*
X1040839Y1023330D01*
Y1026228D01*
X1040840Y1026229D01*
Y1175998D01*
X1034254Y1182584D01*
G01X1072120Y1292460D02*
Y1274020D01*
X1034254Y1236154D01*
Y1182584D01*
G01X1039900Y1417000D02*
X1023202D01*
X1014633Y1425569D01*
X968398D01*
X962136Y1431831D01*
G01X1322000Y1430700D02*
X1310200D01*
X1306500Y1427000D01*
X1300074D01*
X1296374Y1430700D01*
G01X1266474Y1487500D02*
X1257174Y1496800D01*
X1252674D01*
G01X1278574Y1488700D02*
X1272474D01*
X1271274Y1487500D01*
X1266474D01*
G01X1282374Y1464000D02*
Y1467800D01*
X1278574Y1471600D01*
Y1488700D01*
G01X1282374Y1445500D02*
X1292282D01*
X1297089Y1450307D01*
G01X1661626Y1480000D02*
X1309639D01*
X1299939Y1489700D01*
X1288074D01*
X1284624Y1486250D01*
Y1476400D01*
G54D19*
G01X688800Y1463493D02*
X700007D01*
X704700Y1458800D01*
Y1437300D01*
X709191Y1432809D01*
X834950D01*
X849500Y1418259D01*
Y1411000D01*
M02*
